FILE_TYPE = MACRO_DRAWING;
SET COLOR_WIRE YELLOW;
SET COLOR_PROP MONO;
SET COLOR_DOT WHITE;
SET COLOR_ARC YELLOW;
SET COLOR_BODY GREEN;
SET COLOR_NOTE MONO;
SET PROP_DISPLAY VALUE;
SET PAGE_NUMBER P94;
FORCEADD RES..2
R 2
(-300 3650);
FORCEPROP 1 LAST LOCATION R4U2
J 2
(-345 3775);
DISPLAY 0.617021 (-345 3775);
PAINT AQUA (-345 3775);
FORCEPROP 1 LAST PART_NUMBER G21796-112
J 2
(-340 3525);
DISPLAY 0.617021 (-340 3525);
PAINT BLUE (-340 3525);
FORCEPROP 1 LAST VALUE 2.21K
J 2
(-345 3725);
DISPLAY 0.617021 (-345 3725);
PAINT SKYBLUE (-345 3725);
FORCEPROP 1 LAST TOLERANCE 1%
J 2
(-345 3675);
DISPLAY 0.617021 (-345 3675);
PAINT SKYBLUE (-345 3675);
FORCEPROP 1 LAST PACK_TYPE 0402
J 2
(-340 3475);
DISPLAY 0.617021 (-340 3475);
PAINT SKYBLUE (-340 3475);
FORCEPROP 1 LAST MATERIAL CHIP
J 2
(-340 3575);
DISPLAY 0.617021 (-340 3575);
PAINT SKYBLUE (-340 3575);
FORCEPROP 1 LAST WATTAGE 1/16W
J 2
(-340 3625);
DISPLAY 0.617021 (-340 3625);
PAINT SKYBLUE (-340 3625);
FORCEPROP 1 LASTPIN (-300 3550) $PN 2
J 2
(-305 3560);
DISPLAY 0.617021 (-305 3560);
PAINT MONO (-305 3560);
FORCEPROP 1 LASTPIN (-300 3750) $PN 1
J 2
(-305 3712);
DISPLAY 0.617021 (-305 3712);
PAINT MONO (-305 3712);
FORCEPROP 2 LAST SEC_TYPE 0402
J 2
(-350 3875);
PAINT MONO (-350 3875);
DISPLAY INVISIBLE (-350 3875);
FORCEPROP 2 LAST BOM_COST PROC_SIDEBAND
J 2
(-300 3650);
PAINT MONO (-300 3650);
DISPLAY INVISIBLE (-300 3650);
FORCEPROP 2 LAST CDS_LIB mstr_discrete
J 2
(-300 3650);
PAINT ORANGE (-300 3650);
DISPLAY INVISIBLE (-300 3650);
FORCEPROP 2 LAST SEC 1
J 2
(-350 3875);
DISPLAY 0.936170 (-350 3875);
PAINT MONO (-350 3875);
DISPLAY INVISIBLE (-350 3875);
FORCEPROP 2 LAST CDS_LOCATION R4U2
J 2
(-345 3775);
DISPLAY 0.617021 (-345 3775);
PAINT AQUA (-345 3775);
DISPLAY INVISIBLE (-345 3775);
FORCEPROP 1 LAST PATH I100
J 2
(-350 3825);
DISPLAY 0.978723 (-350 3825);
PAINT WHITE (-350 3825);
DISPLAY INVISIBLE (-350 3825);
FORCEPROP 2 LAST ROOM PROC_SIDEBAND
J 2
(-325 3425);
PAINT ORANGE (-325 3425);
DISPLAY INVISIBLE (-325 3425);
FORCEADD OFFPAGE..1
(-1650 3425);
FORCEPROP 2 LAST $XR0 43 
J 0
(-1901 3425);
DISPLAY 0.638298 (-1901 3425);
PAINT MONO (-1901 3425);
FORCEPROP 2 LAST $XR1 44 
J 0
(-1991 3425);
DISPLAY 0.638298 (-1991 3425);
PAINT MONO (-1991 3425);
FORCEPROP 2 LAST $XR2 45 
J 0
(-2081 3425);
DISPLAY 0.638298 (-2081 3425);
PAINT MONO (-2081 3425);
FORCEPROP 2 LAST $XR3 46 
J 0
(-2171 3425);
DISPLAY 0.638298 (-2171 3425);
PAINT MONO (-2171 3425);
FORCEPROP 2 LAST $XR4 47 
J 0
(-2261 3425);
DISPLAY 0.638298 (-2261 3425);
PAINT MONO (-2261 3425);
FORCEPROP 2 LAST $XR5 48 
J 0
(-2351 3425);
DISPLAY 0.638298 (-2351 3425);
PAINT MONO (-2351 3425);
FORCEPROP 2 LAST $XR6 49 
J 0
(-2441 3425);
DISPLAY 0.638298 (-2441 3425);
PAINT MONO (-2441 3425);
FORCEPROP 2 LAST $XR7 50 
J 0
(-2531 3425);
DISPLAY 0.638298 (-2531 3425);
PAINT MONO (-2531 3425);
FORCEPROP 2 LAST $XR8 51 
J 0
(-2621 3425);
DISPLAY 0.638298 (-2621 3425);
PAINT MONO (-2621 3425);
FORCEPROP 2 LAST $XR9 52 
J 0
(-2711 3425);
DISPLAY 0.638298 (-2711 3425);
PAINT MONO (-2711 3425);
FORCEPROP 2 LAST $XR10 53 
J 0
(-1901 3389);
DISPLAY 0.638298 (-1901 3389);
PAINT MONO (-1901 3389);
FORCEPROP 2 LAST $XR11 54 
J 0
(-1991 3389);
DISPLAY 0.638298 (-1991 3389);
PAINT MONO (-1991 3389);
FORCEPROP 2 LAST $XR12 77 
J 0
(-2081 3389);
DISPLAY 0.638298 (-2081 3389);
PAINT MONO (-2081 3389);
FORCEPROP 2 LAST $XR13 78 
J 0
(-2171 3389);
DISPLAY 0.638298 (-2171 3389);
PAINT MONO (-2171 3389);
FORCEPROP 2 LAST $XR14 79 
J 0
(-2261 3389);
DISPLAY 0.638298 (-2261 3389);
PAINT MONO (-2261 3389);
FORCEPROP 2 LAST $XR15 80 
J 0
(-2351 3389);
DISPLAY 0.638298 (-2351 3389);
PAINT MONO (-2351 3389);
FORCEPROP 2 LAST $XR16 81 
J 0
(-2441 3389);
DISPLAY 0.638298 (-2441 3389);
PAINT MONO (-2441 3389);
FORCEPROP 2 LAST $XR17 82 
J 0
(-2531 3389);
DISPLAY 0.638298 (-2531 3389);
PAINT MONO (-2531 3389);
FORCEPROP 2 LAST $XR18 83 
J 0
(-2621 3389);
DISPLAY 0.638298 (-2621 3389);
PAINT MONO (-2621 3389);
FORCEPROP 2 LAST $XR19 84 
J 0
(-1901 3461);
DISPLAY 0.638298 (-1901 3461);
PAINT MONO (-1901 3461);
FORCEPROP 2 LAST $XR20 85 
J 0
(-1991 3461);
DISPLAY 0.638298 (-1991 3461);
PAINT MONO (-1991 3461);
FORCEPROP 2 LAST $XR21 86 
J 0
(-2081 3461);
DISPLAY 0.638298 (-2081 3461);
PAINT MONO (-2081 3461);
FORCEPROP 2 LAST $XR22 87 
J 0
(-2171 3461);
DISPLAY 0.638298 (-2171 3461);
PAINT MONO (-2171 3461);
FORCEPROP 2 LAST $XR23 88 
J 0
(-2261 3461);
DISPLAY 0.638298 (-2261 3461);
PAINT MONO (-2261 3461);
FORCEPROP 2 LAST CDS_LIB mstr_standard
J 0
(-1650 3425);
PAINT MONO (-1650 3425);
DISPLAY INVISIBLE (-1650 3425);
FORCEPROP 1 LAST OFFPAGE TRUE
J 0
(-1325 3300);
PAINT GREEN (-1325 3300);
DISPLAY INVISIBLE (-1325 3300);
FORCEPROP 1 LAST COMMENT_BODY TRUE
J 0
(-1525 3325);
DISPLAY 1.170213 (-1525 3325);
PAINT GREEN (-1525 3325);
DISPLAY INVISIBLE (-1525 3325);
FORCEPROP 2 LAST PATH I101
J 0
(-1900 3500);
DISPLAY 1.021277 (-1900 3500);
PAINT ORANGE (-1900 3500);
DISPLAY INVISIBLE (-1900 3500);
FORCEADD FET_N_DUAL..5
(1400 3950);
FORCEPROP 1 LAST LOCATION Q4U1
J 0
(1600 3950);
DISPLAY 0.617021 (1600 3950);
PAINT AQUA (1600 3950);
FORCEPROP 1 LAST PART_NUMBER E40049-001
J 0
(1000 4150);
DISPLAY 0.617021 (1000 4150);
PAINT BLUE (1000 4150);
FORCEPROP 1 LAST VALUE NTJD4001N
J 0
(1000 4100);
DISPLAY 0.617021 (1000 4100);
PAINT SKYBLUE (1000 4100);
FORCEPROP 1 LAST MATERIAL FET
J 0
(1000 4050);
DISPLAY 0.617021 (1000 4050);
PAINT SKYBLUE (1000 4050);
FORCEPROP 1 LASTPIN (1400 3750) $PN 4
J 2
(1458 3750);
DISPLAY 0.617021 (1458 3750);
PAINT WHITE (1458 3750);
FORCEPROP 1 LASTPIN (1200 3850) $PN 5
J 2
(1203 3865);
DISPLAY 0.617021 (1203 3865);
PAINT WHITE (1203 3865);
FORCEPROP 1 LASTPIN (1400 4150) $PN 3
J 2
(1453 4115);
DISPLAY 0.617021 (1453 4115);
PAINT WHITE (1453 4115);
FORCEPROP 1 LAST PACK_TYPE SMLF
J 0
(1600 3800);
PAINT SKYBLUE (1600 3800);
DISPLAY INVISIBLE (1600 3800);
FORCEPROP 2 LAST SEC_TYPE SMLF
J 0
(1000 4200);
DISPLAY 1.021277 (1000 4200);
PAINT ORANGE (1000 4200);
DISPLAY INVISIBLE (1000 4200);
FORCEPROP 2 LAST CDS_LIB mstr_discrete
J 0
(1400 3950);
PAINT ORANGE (1400 3950);
DISPLAY INVISIBLE (1400 3950);
FORCEPROP 2 LAST BOM_COST PROC_SIDEBAND
J 0
(1400 3950);
PAINT MONO (1400 3950);
DISPLAY INVISIBLE (1400 3950);
FORCEPROP 2 LAST SEC 2
J 0
(1000 4200);
DISPLAY 0.680851 (1000 4200);
PAINT MONO (1000 4200);
DISPLAY INVISIBLE (1000 4200);
FORCEPROP 2 LAST CDS_LOCATION Q4U1
J 0
(1600 3950);
DISPLAY 0.617021 (1600 3950);
PAINT AQUA (1600 3950);
DISPLAY INVISIBLE (1600 3950);
FORCEPROP 1 LAST PATH I102
J 0
(1600 4000);
DISPLAY 0.978723 (1600 4000);
PAINT BLUE (1600 4000);
DISPLAY INVISIBLE (1600 4000);
FORCEPROP 2 LAST ROOM PROC_SIDEBAND
J 0
(1600 4050);
PAINT ORANGE (1600 4050);
DISPLAY INVISIBLE (1600 4050);
FORCEADD PVPP_ABC..1
(175 4300);
FORCEPROP 3 LASTPIN (175 4250) SIG_NAME PVPP_ABC\g
J 0
(185 4260);
DISPLAY 0.659574 (185 4260);
PAINT MONO (185 4260);
DISPLAY INVISIBLE (185 4260);
FORCEPROP 1 LAST VOLTAGE 2.5V
J 0
(130 4257);
DISPLAY 0.340426 (130 4257);
PAINT SKYBLUE (130 4257);
DISPLAY INVISIBLE (130 4257);
FORCEPROP 2 LAST BOM_COST PVPP_KLM_VR
J 0
(250 4400);
PAINT MONO (250 4400);
DISPLAY INVISIBLE (250 4400);
FORCEPROP 2 LAST CDS_LIB mstr_symbols
J 0
(175 4300);
PAINT ORANGE (175 4300);
DISPLAY INVISIBLE (175 4300);
FORCEPROP 1 LAST BODY_TYPE PLUMBING
J 0
(130 4257);
DISPLAY 0.340426 (130 4257);
PAINT GREEN (130 4257);
DISPLAY INVISIBLE (130 4257);
FORCEPROP 1 LAST PATH I103
J 0
(225 4325);
DISPLAY 0.872340 (225 4325);
PAINT AQUA (225 4325);
DISPLAY INVISIBLE (225 4325);
FORCEPROP 2 LAST ROOM PVPP_KLM_VR
J 0
(425 4400);
PAINT ORANGE (425 4400);
DISPLAY INVISIBLE (425 4400);
FORCEPROP 1 LAST HDL_POWER PVPP_ABC
J 1
(175 4350);
DISPLAY 0.872340 (175 4350);
PAINT GREEN (175 4350);
DISPLAY INVISIBLE (175 4350);
FORCEADD RES..2
(750 3575);
FORCEPROP 1 LAST LOCATION R4U4
J 0
(795 3700);
DISPLAY 0.617021 (795 3700);
PAINT AQUA (795 3700);
FORCEPROP 1 LAST PART_NUMBER G21497-023
J 0
(790 3450);
DISPLAY 0.617021 (790 3450);
PAINT BLUE (790 3450);
FORCEPROP 1 LAST VALUE 33.0K
J 0
(795 3650);
DISPLAY 0.617021 (795 3650);
PAINT SKYBLUE (795 3650);
FORCEPROP 1 LAST TOLERANCE 5%
J 0
(795 3600);
DISPLAY 0.617021 (795 3600);
PAINT SKYBLUE (795 3600);
FORCEPROP 1 LAST PACK_TYPE 0402
J 0
(790 3400);
DISPLAY 0.617021 (790 3400);
PAINT SKYBLUE (790 3400);
FORCEPROP 1 LAST MATERIAL CHIP
J 0
(790 3500);
DISPLAY 0.617021 (790 3500);
PAINT SKYBLUE (790 3500);
FORCEPROP 1 LAST WATTAGE 1/16W
J 0
(790 3550);
DISPLAY 0.617021 (790 3550);
PAINT SKYBLUE (790 3550);
FORCEPROP 1 LASTPIN (750 3475) $PN 2
J 0
(755 3485);
DISPLAY 0.617021 (755 3485);
PAINT ORANGE (755 3485);
FORCEPROP 1 LASTPIN (750 3675) $PN 1
J 0
(755 3637);
DISPLAY 0.617021 (755 3637);
PAINT ORANGE (755 3637);
FORCEPROP 2 LAST CDS_LIB mstr_discrete
J 0
(750 3575);
PAINT ORANGE (750 3575);
DISPLAY INVISIBLE (750 3575);
FORCEPROP 2 LAST SEC_TYPE 0402
J 0
(800 3800);
DISPLAY 1.021277 (800 3800);
PAINT ORANGE (800 3800);
DISPLAY INVISIBLE (800 3800);
FORCEPROP 2 LAST SEC 1
J 0
(800 3800);
DISPLAY 0.680851 (800 3800);
PAINT MONO (800 3800);
DISPLAY INVISIBLE (800 3800);
FORCEPROP 2 LAST CDS_LOCATION R4U4
J 0
(795 3700);
DISPLAY 0.617021 (795 3700);
PAINT AQUA (795 3700);
DISPLAY INVISIBLE (795 3700);
FORCEPROP 1 LAST PATH I104
J 0
(800 3750);
DISPLAY 0.978723 (800 3750);
PAINT WHITE (800 3750);
DISPLAY INVISIBLE (800 3750);
FORCEADD GND..1
(750 3225);
FORCEPROP 3 LASTPIN (750 3275) SIG_NAME GND\g
J 0
(760 3285);
DISPLAY 0.659574 (760 3285);
PAINT MONO (760 3285);
DISPLAY INVISIBLE (760 3285);
FORCEPROP 1 LAST VOLTAGE 0
J 0
(750 3225);
PAINT SKYBLUE (750 3225);
DISPLAY INVISIBLE (750 3225);
FORCEPROP 2 LAST CDS_LIB mstr_symbols
J 0
(750 3225);
PAINT ORANGE (750 3225);
DISPLAY INVISIBLE (750 3225);
FORCEPROP 1 LAST SIZE 1B
J 0
(825 3175);
DISPLAY 1.170213 (825 3175);
PAINT GREEN (825 3175);
DISPLAY INVISIBLE (825 3175);
FORCEPROP 1 LAST BODY_TYPE PLUMBING
J 0
(705 3182);
DISPLAY 0.340426 (705 3182);
PAINT GREEN (705 3182);
DISPLAY INVISIBLE (705 3182);
FORCEPROP 1 LAST PATH I105
J 0
(825 3225);
DISPLAY 0.872340 (825 3225);
PAINT AQUA (825 3225);
DISPLAY INVISIBLE (825 3225);
FORCEPROP 1 LAST HDL_POWER GND
J 0
(750 3375);
DISPLAY 1.170213 (750 3375);
PAINT GREEN (750 3375);
DISPLAY INVISIBLE (750 3375);
FORCEADD OFFPAGE..5
R 2
(-675 2300);
FORCEPROP 2 LAST $XR0 95 
J 0
(-486 2300);
DISPLAY 0.638298 (-486 2300);
PAINT MONO (-486 2300);
FORCEPROP 2 LAST $XR1 21 
J 0
(-396 2300);
DISPLAY 0.638298 (-396 2300);
PAINT MONO (-396 2300);
FORCEPROP 2 LAST $XR2 152 
J 0
(-306 2300);
DISPLAY 0.638298 (-306 2300);
PAINT MONO (-306 2300);
FORCEPROP 2 LAST CDS_LIB mstr_standard
J 1
(-675 2300);
PAINT ORANGE (-675 2300);
DISPLAY INVISIBLE (-675 2300);
FORCEPROP 2 LAST ROOM PROC_SIDEBAND
J 2
(-365 2330);
DISPLAY 0.978723 (-365 2330);
PAINT ORANGE (-365 2330);
DISPLAY INVISIBLE (-365 2330);
FORCEPROP 1 LAST OFFPAGE TRUE
J 2
(-1000 2175);
PAINT GREEN (-1000 2175);
DISPLAY INVISIBLE (-1000 2175);
FORCEPROP 1 LAST COMMENT_BODY TRUE
J 2
(-775 2225);
DISPLAY 0.978723 (-775 2225);
PAINT GREEN (-775 2225);
DISPLAY INVISIBLE (-775 2225);
FORCEPROP 2 LAST PATH I39
J 0
(-380 2350);
DISPLAY 1.021277 (-380 2350);
PAINT ORANGE (-380 2350);
DISPLAY INVISIBLE (-380 2350);
FORCEADD GND..1
(-1425 1750);
FORCEPROP 3 LASTPIN (-1425 1800) SIG_NAME GND\g
J 0
(-1415 1810);
DISPLAY 0.659574 (-1415 1810);
PAINT MONO (-1415 1810);
DISPLAY INVISIBLE (-1415 1810);
FORCEPROP 1 LAST VOLTAGE 0
J 0
(-1425 1750);
PAINT SKYBLUE (-1425 1750);
DISPLAY INVISIBLE (-1425 1750);
FORCEPROP 1 LAST SIZE 1B
J 0
(-1350 1700);
DISPLAY 1.170213 (-1350 1700);
PAINT GREEN (-1350 1700);
DISPLAY INVISIBLE (-1350 1700);
FORCEPROP 2 LAST CDS_LIB mstr_symbols
J 0
(-1425 1750);
PAINT ORANGE (-1425 1750);
DISPLAY INVISIBLE (-1425 1750);
FORCEPROP 1 LAST BODY_TYPE PLUMBING
J 0
(-1470 1707);
DISPLAY 0.340426 (-1470 1707);
PAINT GREEN (-1470 1707);
DISPLAY INVISIBLE (-1470 1707);
FORCEPROP 1 LAST PATH I47
J 0
(-1350 1750);
DISPLAY 0.872340 (-1350 1750);
PAINT AQUA (-1350 1750);
DISPLAY INVISIBLE (-1350 1750);
FORCEPROP 2 LAST ROOM PROCHOT_MEMHOT_ISO
J 0
(-1800 1825);
PAINT ORANGE (-1800 1825);
DISPLAY INVISIBLE (-1800 1825);
FORCEPROP 1 LAST HDL_POWER GND
J 0
(-1425 1900);
DISPLAY 1.170213 (-1425 1900);
PAINT GREEN (-1425 1900);
DISPLAY INVISIBLE (-1425 1900);
FORCEADD FET_N_DUAL..5
(-2150 1925);
FORCEPROP 1 LAST LOCATION Q3U1
J 0
(-2025 1750);
DISPLAY 0.617021 (-2025 1750);
PAINT AQUA (-2025 1750);
FORCEPROP 1 LAST PART_NUMBER E40049-001
J 0
(-2025 1600);
DISPLAY 0.617021 (-2025 1600);
PAINT BLUE (-2025 1600);
FORCEPROP 1 LAST VALUE NTJD4001N
J 0
(-2025 1700);
DISPLAY 0.617021 (-2025 1700);
PAINT SKYBLUE (-2025 1700);
FORCEPROP 1 LAST MATERIAL FET
J 0
(-2025 1650);
DISPLAY 0.617021 (-2025 1650);
PAINT SKYBLUE (-2025 1650);
FORCEPROP 1 LASTPIN (-2150 1725) $PN 1
J 2
(-2092 1725);
DISPLAY 0.617021 (-2092 1725);
PAINT MONO (-2092 1725);
FORCEPROP 1 LASTPIN (-2350 1825) $PN 2
J 2
(-2347 1840);
DISPLAY 0.617021 (-2347 1840);
PAINT MONO (-2347 1840);
FORCEPROP 1 LASTPIN (-2150 2125) $PN 6
J 2
(-2097 2090);
DISPLAY 0.617021 (-2097 2090);
PAINT MONO (-2097 2090);
FORCEPROP 1 LAST PACK_TYPE SMLF
J 0
(-1950 1775);
PAINT SKYBLUE (-1950 1775);
DISPLAY INVISIBLE (-1950 1775);
FORCEPROP 2 LAST CDS_LIB mstr_discrete
J 0
(-2150 1925);
PAINT ORANGE (-2150 1925);
DISPLAY INVISIBLE (-2150 1925);
FORCEPROP 2 LAST SEC_TYPE SMLF
J 0
(-1950 2025);
DISPLAY 1.404255 (-1950 2025);
PAINT ORANGE (-1950 2025);
DISPLAY INVISIBLE (-1950 2025);
FORCEPROP 2 LAST SEC 1
J 0
(-1950 2025);
DISPLAY 0.936170 (-1950 2025);
PAINT MONO (-1950 2025);
DISPLAY INVISIBLE (-1950 2025);
FORCEPROP 2 LAST CDS_LOCATION Q3U1
J 0
(-2025 1750);
DISPLAY 0.617021 (-2025 1750);
PAINT AQUA (-2025 1750);
DISPLAY INVISIBLE (-2025 1750);
FORCEPROP 1 LAST PATH I49
J 0
(-1950 1975);
DISPLAY 0.978723 (-1950 1975);
PAINT BLUE (-1950 1975);
DISPLAY INVISIBLE (-1950 1975);
FORCEPROP 2 LAST ROOM PROC_SIDEBAND
J 0
(-2150 1965);
DISPLAY 0.787234 (-2150 1965);
PAINT SKYBLUE (-2150 1965);
DISPLAY INVISIBLE (-2150 1965);
FORCEADD P3V3..1
(-2150 2575);
FORCEPROP 3 LASTPIN (-2150 2525) SIG_NAME P3V3\g
J 0
(-2140 2535);
DISPLAY 0.659574 (-2140 2535);
PAINT MONO (-2140 2535);
DISPLAY INVISIBLE (-2140 2535);
FORCEPROP 1 LAST VOLTAGE +3.3
J 0
(-2150 2575);
PAINT SKYBLUE (-2150 2575);
DISPLAY INVISIBLE (-2150 2575);
FORCEPROP 2 LAST CDS_LIB mstr_symbols
J 0
(-2150 2575);
PAINT ORANGE (-2150 2575);
DISPLAY INVISIBLE (-2150 2575);
FORCEPROP 1 LAST SIZE 1B
J 0
(-2105 2597);
DISPLAY 0.553191 (-2105 2597);
PAINT GREEN (-2105 2597);
DISPLAY INVISIBLE (-2105 2597);
FORCEPROP 1 LAST BODY_TYPE PLUMBING
J 0
(-2195 2532);
DISPLAY 0.468085 (-2195 2532);
PAINT GREEN (-2195 2532);
DISPLAY INVISIBLE (-2195 2532);
FORCEPROP 1 LAST PATH I50
J 0
(-2105 2577);
DISPLAY 0.340426 (-2105 2577);
PAINT GREEN (-2105 2577);
DISPLAY INVISIBLE (-2105 2577);
FORCEPROP 2 LAST ROOM PROC_SIDEBAND
J 0
(-2300 2675);
PAINT PEACH (-2300 2675);
DISPLAY INVISIBLE (-2300 2675);
FORCEPROP 1 LAST HDL_POWER P3V3
J 0
(-2475 2450);
DISPLAY 1.170213 (-2475 2450);
PAINT GREEN (-2475 2450);
DISPLAY INVISIBLE (-2475 2450);
FORCEADD RES..2
R 2
(-2150 2375);
FORCEPROP 1 LAST LOCATION R7G7
J 2
(-2195 2450);
DISPLAY 0.617021 (-2195 2450);
PAINT AQUA (-2195 2450);
FORCEPROP 1 LAST PART_NUMBER G21796-072
R 1
J 0
(-2090 2250);
DISPLAY 0.617021 (-2090 2250);
PAINT BLUE (-2090 2250);
FORCEPROP 1 LAST VALUE 4.75K
J 2
(-2195 2400);
DISPLAY 0.617021 (-2195 2400);
PAINT SKYBLUE (-2195 2400);
FORCEPROP 1 LAST TOLERANCE 1%
J 2
(-2195 2350);
DISPLAY 0.617021 (-2195 2350);
PAINT SKYBLUE (-2195 2350);
FORCEPROP 1 LAST PACK_TYPE 0402
J 2
(-2190 2200);
DISPLAY 0.617021 (-2190 2200);
PAINT SKYBLUE (-2190 2200);
FORCEPROP 1 LAST MATERIAL CHIP
J 2
(-2190 2250);
DISPLAY 0.617021 (-2190 2250);
PAINT SKYBLUE (-2190 2250);
FORCEPROP 1 LAST WATTAGE 1/16W
J 2
(-2190 2300);
DISPLAY 0.617021 (-2190 2300);
PAINT SKYBLUE (-2190 2300);
FORCEPROP 1 LASTPIN (-2150 2275) $PN 2
J 2
(-2155 2285);
DISPLAY 0.617021 (-2155 2285);
PAINT MONO (-2155 2285);
FORCEPROP 1 LASTPIN (-2150 2475) $PN 1
J 2
(-2155 2437);
DISPLAY 0.617021 (-2155 2437);
PAINT MONO (-2155 2437);
FORCEPROP 2 LAST CDS_LIB mstr_discrete
J 2
(-2150 2375);
DISPLAY 1.361702 (-2150 2375);
PAINT ORANGE (-2150 2375);
DISPLAY INVISIBLE (-2150 2375);
FORCEPROP 2 LAST BOM_COST PROC_SIDEBAND
J 0
(-2150 2375);
PAINT MONO (-2150 2375);
DISPLAY INVISIBLE (-2150 2375);
FORCEPROP 2 LAST CDS_SEC 1
J 1
(-2200 2600);
DISPLAY 1.404255 (-2200 2600);
PAINT ORANGE (-2200 2600);
DISPLAY INVISIBLE (-2200 2600);
FORCEPROP 2 LAST $SEC 1
J 1
(-2200 2600);
DISPLAY 0.936170 (-2200 2600);
PAINT MONO (-2200 2600);
DISPLAY INVISIBLE (-2200 2600);
FORCEPROP 2 LAST CDS_LOCATION R7G7
J 2
(-2195 2450);
DISPLAY 0.617021 (-2195 2450);
PAINT AQUA (-2195 2450);
DISPLAY INVISIBLE (-2195 2450);
FORCEPROP 1 LAST PATH I51
J 2
(-2200 2550);
DISPLAY 0.978723 (-2200 2550);
PAINT WHITE (-2200 2550);
DISPLAY INVISIBLE (-2200 2550);
FORCEPROP 2 LAST ROOM PROC_SIDEBAND
J 2
(-2200 2550);
PAINT PEACH (-2200 2550);
DISPLAY INVISIBLE (-2200 2550);
FORCEADD GND..1
(-2150 1650);
FORCEPROP 3 LASTPIN (-2150 1700) SIG_NAME GND\g
J 0
(-2140 1710);
DISPLAY 0.659574 (-2140 1710);
PAINT MONO (-2140 1710);
DISPLAY INVISIBLE (-2140 1710);
FORCEPROP 1 LAST VOLTAGE 0
J 0
(-2150 1650);
PAINT SKYBLUE (-2150 1650);
DISPLAY INVISIBLE (-2150 1650);
FORCEPROP 1 LAST SIZE 1B
J 0
(-2075 1600);
DISPLAY 1.170213 (-2075 1600);
PAINT GREEN (-2075 1600);
DISPLAY INVISIBLE (-2075 1600);
FORCEPROP 2 LAST CDS_LIB mstr_symbols
J 0
(-2150 1650);
PAINT ORANGE (-2150 1650);
DISPLAY INVISIBLE (-2150 1650);
FORCEPROP 1 LAST BODY_TYPE PLUMBING
J 0
(-2195 1607);
DISPLAY 0.340426 (-2195 1607);
PAINT GREEN (-2195 1607);
DISPLAY INVISIBLE (-2195 1607);
FORCEPROP 1 LAST PATH I56
J 0
(-2075 1650);
DISPLAY 0.872340 (-2075 1650);
PAINT AQUA (-2075 1650);
DISPLAY INVISIBLE (-2075 1650);
FORCEPROP 2 LAST ROOM PROCHOT_MEMHOT_ISO
J 0
(-2525 1725);
PAINT ORANGE (-2525 1725);
DISPLAY INVISIBLE (-2525 1725);
FORCEPROP 1 LAST HDL_POWER GND
J 0
(-2150 1800);
DISPLAY 1.170213 (-2150 1800);
PAINT GREEN (-2150 1800);
DISPLAY INVISIBLE (-2150 1800);
FORCEADD OFFPAGE..1
(-3325 1825);
FORCEPROP 2 LAST $XR0 215 
J 0
(-3577 1825);
DISPLAY 0.638298 (-3577 1825);
PAINT MONO (-3577 1825);
FORCEPROP 2 LAST $XR1 119 
J 0
(-3697 1825);
DISPLAY 0.638298 (-3697 1825);
PAINT MONO (-3697 1825);
FORCEPROP 2 LAST $XR2 145 
J 0
(-3577 1789);
DISPLAY 0.638298 (-3577 1789);
PAINT MONO (-3577 1789);
FORCEPROP 2 LAST CDS_LIB mstr_standard
J 0
(-3325 1825);
PAINT ORANGE (-3325 1825);
DISPLAY INVISIBLE (-3325 1825);
FORCEPROP 2 LAST ROOM PROCHOT_MEMHOT_ISO
J 0
(-3575 1875);
DISPLAY 0.978723 (-3575 1875);
PAINT ORANGE (-3575 1875);
DISPLAY INVISIBLE (-3575 1875);
FORCEPROP 1 LAST OFFPAGE TRUE
J 0
(-3000 1700);
PAINT GREEN (-3000 1700);
DISPLAY INVISIBLE (-3000 1700);
FORCEPROP 1 LAST COMMENT_BODY TRUE
J 0
(-3200 1725);
DISPLAY 0.978723 (-3200 1725);
PAINT PEACH (-3200 1725);
DISPLAY INVISIBLE (-3200 1725);
FORCEPROP 2 LAST PATH I59
J 0
(-3575 1875);
DISPLAY 1.021277 (-3575 1875);
PAINT ORANGE (-3575 1875);
DISPLAY INVISIBLE (-3575 1875);
FORCEADD FET_N_DUAL..5
(-2150 825);
FORCEPROP 1 LAST LOCATION Q7E1
J 0
(-2025 650);
DISPLAY 0.617021 (-2025 650);
PAINT AQUA (-2025 650);
FORCEPROP 1 LAST PART_NUMBER E40049-001
J 0
(-2025 500);
DISPLAY 0.617021 (-2025 500);
PAINT BLUE (-2025 500);
FORCEPROP 1 LAST VALUE NTJD4001N
J 0
(-2025 600);
DISPLAY 0.617021 (-2025 600);
PAINT SKYBLUE (-2025 600);
FORCEPROP 1 LAST MATERIAL FET
J 0
(-2025 550);
DISPLAY 0.617021 (-2025 550);
PAINT SKYBLUE (-2025 550);
FORCEPROP 1 LASTPIN (-2150 625) $PN 1
J 2
(-2092 625);
DISPLAY 0.617021 (-2092 625);
PAINT MONO (-2092 625);
FORCEPROP 1 LASTPIN (-2350 725) $PN 2
J 2
(-2347 740);
DISPLAY 0.617021 (-2347 740);
PAINT MONO (-2347 740);
FORCEPROP 1 LASTPIN (-2150 1025) $PN 6
J 2
(-2097 990);
DISPLAY 0.617021 (-2097 990);
PAINT MONO (-2097 990);
FORCEPROP 1 LAST PACK_TYPE SMLF
J 0
(-1950 675);
PAINT SKYBLUE (-1950 675);
DISPLAY INVISIBLE (-1950 675);
FORCEPROP 2 LAST CDS_LIB mstr_discrete
J 0
(-2150 825);
PAINT ORANGE (-2150 825);
DISPLAY INVISIBLE (-2150 825);
FORCEPROP 2 LAST SEC_TYPE SMLF
J 0
(-1950 925);
DISPLAY 1.404255 (-1950 925);
PAINT ORANGE (-1950 925);
DISPLAY INVISIBLE (-1950 925);
FORCEPROP 2 LAST SEC 1
J 0
(-1950 925);
DISPLAY 0.936170 (-1950 925);
PAINT MONO (-1950 925);
DISPLAY INVISIBLE (-1950 925);
FORCEPROP 2 LAST CDS_LOCATION Q7E1
J 0
(-2025 650);
DISPLAY 0.617021 (-2025 650);
PAINT AQUA (-2025 650);
DISPLAY INVISIBLE (-2025 650);
FORCEPROP 1 LAST PATH I60
J 0
(-1950 875);
DISPLAY 0.978723 (-1950 875);
PAINT BLUE (-1950 875);
DISPLAY INVISIBLE (-1950 875);
FORCEPROP 2 LAST ROOM PROC_SIDEBAND
J 0
(-2150 865);
DISPLAY 0.787234 (-2150 865);
PAINT SKYBLUE (-2150 865);
DISPLAY INVISIBLE (-2150 865);
FORCEADD OFFPAGE..5
R 2
(-675 1200);
FORCEPROP 2 LAST $XR0 95 
J 0
(-486 1200);
DISPLAY 0.638298 (-486 1200);
PAINT MONO (-486 1200);
FORCEPROP 2 LAST $XR1 21 
J 0
(-396 1200);
DISPLAY 0.638298 (-396 1200);
PAINT MONO (-396 1200);
FORCEPROP 2 LAST $XR2 152 
J 0
(-306 1200);
DISPLAY 0.638298 (-306 1200);
PAINT MONO (-306 1200);
FORCEPROP 2 LAST ROOM PROCHOT_MEMHOT_ISO
J 2
(-365 1230);
DISPLAY 0.978723 (-365 1230);
PAINT ORANGE (-365 1230);
DISPLAY INVISIBLE (-365 1230);
FORCEPROP 2 LAST CDS_LIB mstr_standard
J 1
(-675 1200);
PAINT ORANGE (-675 1200);
DISPLAY INVISIBLE (-675 1200);
FORCEPROP 1 LAST OFFPAGE TRUE
J 2
(-1000 1075);
PAINT GREEN (-1000 1075);
DISPLAY INVISIBLE (-1000 1075);
FORCEPROP 1 LAST COMMENT_BODY TRUE
J 2
(-775 1125);
DISPLAY 0.978723 (-775 1125);
PAINT GREEN (-775 1125);
DISPLAY INVISIBLE (-775 1125);
FORCEPROP 2 LAST PATH I61
J 0
(-380 1250);
DISPLAY 1.021277 (-380 1250);
PAINT ORANGE (-380 1250);
DISPLAY INVISIBLE (-380 1250);
FORCEADD GND..1
(-1425 650);
FORCEPROP 3 LASTPIN (-1425 700) SIG_NAME GND\g
J 0
(-1415 710);
DISPLAY 0.659574 (-1415 710);
PAINT MONO (-1415 710);
DISPLAY INVISIBLE (-1415 710);
FORCEPROP 1 LAST VOLTAGE 0
J 0
(-1425 650);
PAINT SKYBLUE (-1425 650);
DISPLAY INVISIBLE (-1425 650);
FORCEPROP 1 LAST SIZE 1B
J 0
(-1350 600);
DISPLAY 1.170213 (-1350 600);
PAINT GREEN (-1350 600);
DISPLAY INVISIBLE (-1350 600);
FORCEPROP 2 LAST CDS_LIB mstr_symbols
J 0
(-1425 650);
PAINT ORANGE (-1425 650);
DISPLAY INVISIBLE (-1425 650);
FORCEPROP 1 LAST BODY_TYPE PLUMBING
J 0
(-1470 607);
DISPLAY 0.340426 (-1470 607);
PAINT GREEN (-1470 607);
DISPLAY INVISIBLE (-1470 607);
FORCEPROP 1 LAST PATH I63
J 0
(-1350 650);
DISPLAY 0.872340 (-1350 650);
PAINT AQUA (-1350 650);
DISPLAY INVISIBLE (-1350 650);
FORCEPROP 2 LAST ROOM PROCHOT_MEMHOT_ISO
J 0
(-1800 725);
PAINT ORANGE (-1800 725);
DISPLAY INVISIBLE (-1800 725);
FORCEPROP 1 LAST HDL_POWER GND
J 0
(-1425 800);
DISPLAY 1.170213 (-1425 800);
PAINT GREEN (-1425 800);
DISPLAY INVISIBLE (-1425 800);
FORCEADD FET_N_DUAL..5
(-1425 950);
FORCEPROP 1 LAST LOCATION Q7E1
J 0
(-1275 800);
DISPLAY 0.617021 (-1275 800);
PAINT AQUA (-1275 800);
FORCEPROP 1 LAST PART_NUMBER E40049-001
J 0
(-1275 650);
DISPLAY 0.617021 (-1275 650);
PAINT BLUE (-1275 650);
FORCEPROP 1 LAST VALUE NTJD4001N
J 0
(-1275 750);
DISPLAY 0.617021 (-1275 750);
PAINT SKYBLUE (-1275 750);
FORCEPROP 1 LAST MATERIAL FET
J 0
(-1275 700);
DISPLAY 0.617021 (-1275 700);
PAINT SKYBLUE (-1275 700);
FORCEPROP 1 LASTPIN (-1425 750) $PN 4
J 2
(-1367 750);
DISPLAY 0.617021 (-1367 750);
PAINT MONO (-1367 750);
FORCEPROP 1 LASTPIN (-1625 850) $PN 5
J 2
(-1622 865);
DISPLAY 0.617021 (-1622 865);
PAINT MONO (-1622 865);
FORCEPROP 1 LASTPIN (-1425 1150) $PN 3
J 2
(-1372 1115);
DISPLAY 0.617021 (-1372 1115);
PAINT MONO (-1372 1115);
FORCEPROP 1 LAST PACK_TYPE SMLF
J 0
(-1225 800);
PAINT SKYBLUE (-1225 800);
DISPLAY INVISIBLE (-1225 800);
FORCEPROP 2 LAST CDS_LIB mstr_discrete
J 0
(-1425 950);
PAINT ORANGE (-1425 950);
DISPLAY INVISIBLE (-1425 950);
FORCEPROP 2 LAST SEC_TYPE SMLF
J 0
(-1225 1050);
DISPLAY 1.404255 (-1225 1050);
PAINT ORANGE (-1225 1050);
DISPLAY INVISIBLE (-1225 1050);
FORCEPROP 2 LAST SEC 2
J 0
(-1225 1050);
DISPLAY 0.936170 (-1225 1050);
PAINT MONO (-1225 1050);
DISPLAY INVISIBLE (-1225 1050);
FORCEPROP 2 LAST CDS_LOCATION Q7E1
J 0
(-1275 800);
DISPLAY 0.617021 (-1275 800);
PAINT AQUA (-1275 800);
DISPLAY INVISIBLE (-1275 800);
FORCEPROP 1 LAST PATH I64
J 0
(-1225 1000);
DISPLAY 0.978723 (-1225 1000);
PAINT BLUE (-1225 1000);
DISPLAY INVISIBLE (-1225 1000);
FORCEPROP 2 LAST ROOM PROC_SIDEBAND
J 0
(-1425 990);
DISPLAY 0.787234 (-1425 990);
PAINT SKYBLUE (-1425 990);
DISPLAY INVISIBLE (-1425 990);
FORCEADD P3V3..1
(-2150 1475);
FORCEPROP 3 LASTPIN (-2150 1425) SIG_NAME P3V3\g
J 0
(-2140 1435);
DISPLAY 0.659574 (-2140 1435);
PAINT MONO (-2140 1435);
DISPLAY INVISIBLE (-2140 1435);
FORCEPROP 1 LAST VOLTAGE +3.3
J 0
(-2150 1475);
PAINT SKYBLUE (-2150 1475);
DISPLAY INVISIBLE (-2150 1475);
FORCEPROP 1 LAST SIZE 1B
J 0
(-2105 1497);
DISPLAY 0.553191 (-2105 1497);
PAINT GREEN (-2105 1497);
DISPLAY INVISIBLE (-2105 1497);
FORCEPROP 2 LAST CDS_LIB mstr_symbols
J 0
(-2150 1475);
PAINT ORANGE (-2150 1475);
DISPLAY INVISIBLE (-2150 1475);
FORCEPROP 1 LAST BODY_TYPE PLUMBING
J 0
(-2195 1432);
DISPLAY 0.468085 (-2195 1432);
PAINT GREEN (-2195 1432);
DISPLAY INVISIBLE (-2195 1432);
FORCEPROP 1 LAST PATH I65
J 0
(-2105 1477);
DISPLAY 0.340426 (-2105 1477);
PAINT GREEN (-2105 1477);
DISPLAY INVISIBLE (-2105 1477);
FORCEPROP 2 LAST ROOM PROCHOT_MEMHOT_ISO
J 0
(-2300 1575);
PAINT PEACH (-2300 1575);
DISPLAY INVISIBLE (-2300 1575);
FORCEPROP 1 LAST HDL_POWER P3V3
J 0
(-2475 1350);
DISPLAY 1.170213 (-2475 1350);
PAINT GREEN (-2475 1350);
DISPLAY INVISIBLE (-2475 1350);
FORCEADD RES..2
R 2
(-2150 1275);
FORCEPROP 1 LAST LOCATION R3R4
J 2
(-2195 1350);
DISPLAY 0.617021 (-2195 1350);
PAINT AQUA (-2195 1350);
FORCEPROP 1 LAST PART_NUMBER G21796-072
R 1
J 0
(-2090 1150);
DISPLAY 0.617021 (-2090 1150);
PAINT BLUE (-2090 1150);
FORCEPROP 1 LAST VALUE 4.75K
J 2
(-2195 1300);
DISPLAY 0.617021 (-2195 1300);
PAINT SKYBLUE (-2195 1300);
FORCEPROP 1 LAST TOLERANCE 1%
J 2
(-2195 1250);
DISPLAY 0.617021 (-2195 1250);
PAINT SKYBLUE (-2195 1250);
FORCEPROP 1 LAST PACK_TYPE 0402
J 2
(-2190 1100);
DISPLAY 0.617021 (-2190 1100);
PAINT SKYBLUE (-2190 1100);
FORCEPROP 1 LAST MATERIAL CHIP
J 2
(-2190 1150);
DISPLAY 0.617021 (-2190 1150);
PAINT SKYBLUE (-2190 1150);
FORCEPROP 1 LAST WATTAGE 1/16W
J 2
(-2190 1200);
DISPLAY 0.617021 (-2190 1200);
PAINT SKYBLUE (-2190 1200);
FORCEPROP 1 LASTPIN (-2150 1175) $PN 2
J 2
(-2155 1185);
DISPLAY 0.617021 (-2155 1185);
PAINT MONO (-2155 1185);
FORCEPROP 1 LASTPIN (-2150 1375) $PN 1
J 2
(-2155 1337);
DISPLAY 0.617021 (-2155 1337);
PAINT MONO (-2155 1337);
FORCEPROP 2 LAST CDS_LIB mstr_discrete
J 2
(-2150 1275);
DISPLAY 1.361702 (-2150 1275);
PAINT ORANGE (-2150 1275);
DISPLAY INVISIBLE (-2150 1275);
FORCEPROP 2 LAST BOM_COST PROC_SIDEBAND
J 0
(-2150 1275);
PAINT MONO (-2150 1275);
DISPLAY INVISIBLE (-2150 1275);
FORCEPROP 2 LAST CDS_SEC 1
J 1
(-2200 1500);
DISPLAY 1.404255 (-2200 1500);
PAINT ORANGE (-2200 1500);
DISPLAY INVISIBLE (-2200 1500);
FORCEPROP 2 LAST $SEC 1
J 1
(-2200 1500);
DISPLAY 0.936170 (-2200 1500);
PAINT MONO (-2200 1500);
DISPLAY INVISIBLE (-2200 1500);
FORCEPROP 2 LAST CDS_LOCATION R3R4
J 2
(-2195 1350);
DISPLAY 0.617021 (-2195 1350);
PAINT AQUA (-2195 1350);
DISPLAY INVISIBLE (-2195 1350);
FORCEPROP 1 LAST PATH I66
J 2
(-2200 1450);
DISPLAY 0.978723 (-2200 1450);
PAINT WHITE (-2200 1450);
DISPLAY INVISIBLE (-2200 1450);
FORCEPROP 2 LAST ROOM PROC_SIDEBAND
J 2
(-2200 1450);
PAINT PEACH (-2200 1450);
DISPLAY INVISIBLE (-2200 1450);
FORCEADD GND..1
(-2150 550);
FORCEPROP 3 LASTPIN (-2150 600) SIG_NAME GND\g
J 0
(-2140 610);
DISPLAY 0.659574 (-2140 610);
PAINT MONO (-2140 610);
DISPLAY INVISIBLE (-2140 610);
FORCEPROP 1 LAST VOLTAGE 0
J 0
(-2150 550);
PAINT SKYBLUE (-2150 550);
DISPLAY INVISIBLE (-2150 550);
FORCEPROP 1 LAST SIZE 1B
J 0
(-2075 500);
DISPLAY 1.170213 (-2075 500);
PAINT GREEN (-2075 500);
DISPLAY INVISIBLE (-2075 500);
FORCEPROP 2 LAST CDS_LIB mstr_symbols
J 0
(-2150 550);
PAINT ORANGE (-2150 550);
DISPLAY INVISIBLE (-2150 550);
FORCEPROP 1 LAST BODY_TYPE PLUMBING
J 0
(-2195 507);
DISPLAY 0.340426 (-2195 507);
PAINT GREEN (-2195 507);
DISPLAY INVISIBLE (-2195 507);
FORCEPROP 1 LAST PATH I67
J 0
(-2075 550);
DISPLAY 0.872340 (-2075 550);
PAINT AQUA (-2075 550);
DISPLAY INVISIBLE (-2075 550);
FORCEPROP 2 LAST ROOM PROCHOT_MEMHOT_ISO
J 0
(-2525 625);
PAINT ORANGE (-2525 625);
DISPLAY INVISIBLE (-2525 625);
FORCEPROP 1 LAST HDL_POWER GND
J 0
(-2150 700);
DISPLAY 1.170213 (-2150 700);
PAINT GREEN (-2150 700);
DISPLAY INVISIBLE (-2150 700);
FORCEADD OFFPAGE..1
(-3325 725);
FORCEPROP 2 LAST $XR0 218 
J 0
(-3577 725);
DISPLAY 0.638298 (-3577 725);
PAINT MONO (-3577 725);
FORCEPROP 2 LAST $XR1 119 
J 0
(-3697 725);
DISPLAY 0.638298 (-3697 725);
PAINT MONO (-3697 725);
FORCEPROP 2 LAST $XR2 144 
J 0
(-3577 689);
DISPLAY 0.638298 (-3577 689);
PAINT MONO (-3577 689);
FORCEPROP 2 LAST CDS_LIB mstr_standard
J 0
(-3325 725);
PAINT ORANGE (-3325 725);
DISPLAY INVISIBLE (-3325 725);
FORCEPROP 2 LAST ROOM PROCHOT_MEMHOT_ISO
J 0
(-3575 775);
DISPLAY 0.978723 (-3575 775);
PAINT ORANGE (-3575 775);
DISPLAY INVISIBLE (-3575 775);
FORCEPROP 1 LAST OFFPAGE TRUE
J 0
(-3000 600);
PAINT GREEN (-3000 600);
DISPLAY INVISIBLE (-3000 600);
FORCEPROP 1 LAST COMMENT_BODY TRUE
J 0
(-3200 625);
DISPLAY 0.978723 (-3200 625);
PAINT PEACH (-3200 625);
DISPLAY INVISIBLE (-3200 625);
FORCEPROP 2 LAST PATH I68
J 0
(-3575 775);
DISPLAY 1.021277 (-3575 775);
PAINT ORANGE (-3575 775);
DISPLAY INVISIBLE (-3575 775);
FORCEADD FET_N_DUAL..5
(1175 1975);
FORCEPROP 1 LAST LOCATION Q7E2
J 0
(1300 1800);
DISPLAY 0.617021 (1300 1800);
PAINT AQUA (1300 1800);
FORCEPROP 1 LAST PART_NUMBER E40049-001
J 0
(1300 1650);
DISPLAY 0.617021 (1300 1650);
PAINT BLUE (1300 1650);
FORCEPROP 1 LAST VALUE NTJD4001N
J 0
(1300 1750);
DISPLAY 0.617021 (1300 1750);
PAINT SKYBLUE (1300 1750);
FORCEPROP 1 LAST MATERIAL FET
J 0
(1300 1700);
DISPLAY 0.617021 (1300 1700);
PAINT SKYBLUE (1300 1700);
FORCEPROP 1 LASTPIN (1175 1775) $PN 1
J 2
(1233 1775);
DISPLAY 0.617021 (1233 1775);
PAINT MONO (1233 1775);
FORCEPROP 1 LASTPIN (975 1875) $PN 2
J 2
(978 1890);
DISPLAY 0.617021 (978 1890);
PAINT MONO (978 1890);
FORCEPROP 1 LASTPIN (1175 2175) $PN 6
J 2
(1228 2140);
DISPLAY 0.617021 (1228 2140);
PAINT MONO (1228 2140);
FORCEPROP 1 LAST PACK_TYPE SMLF
J 0
(1375 1825);
PAINT SKYBLUE (1375 1825);
DISPLAY INVISIBLE (1375 1825);
FORCEPROP 2 LAST SEC_TYPE SMLF
J 0
(1375 2075);
DISPLAY 1.404255 (1375 2075);
PAINT ORANGE (1375 2075);
DISPLAY INVISIBLE (1375 2075);
FORCEPROP 2 LAST CDS_LIB mstr_discrete
J 0
(1175 1975);
PAINT ORANGE (1175 1975);
DISPLAY INVISIBLE (1175 1975);
FORCEPROP 2 LAST SEC 1
J 0
(1375 2075);
DISPLAY 0.936170 (1375 2075);
PAINT MONO (1375 2075);
DISPLAY INVISIBLE (1375 2075);
FORCEPROP 2 LAST CDS_LOCATION Q7E2
J 0
(1300 1800);
DISPLAY 0.617021 (1300 1800);
PAINT AQUA (1300 1800);
DISPLAY INVISIBLE (1300 1800);
FORCEPROP 1 LAST PATH I69
J 0
(1375 2025);
DISPLAY 0.978723 (1375 2025);
PAINT BLUE (1375 2025);
DISPLAY INVISIBLE (1375 2025);
FORCEPROP 2 LAST ROOM PROC_SIDEBAND
J 0
(1175 2015);
DISPLAY 0.787234 (1175 2015);
PAINT SKYBLUE (1175 2015);
DISPLAY INVISIBLE (1175 2015);
FORCEADD OFFPAGE..5
R 2
(2650 2350);
FORCEPROP 2 LAST $XR0 55 
J 0
(2839 2350);
DISPLAY 0.638298 (2839 2350);
PAINT MONO (2839 2350);
FORCEPROP 2 LAST $XR1 95 
J 0
(2929 2350);
DISPLAY 0.638298 (2929 2350);
PAINT MONO (2929 2350);
FORCEPROP 2 LAST $XR2 152 
J 0
(3019 2350);
DISPLAY 0.638298 (3019 2350);
PAINT MONO (3019 2350);
FORCEPROP 2 LAST CDS_LIB mstr_standard
J 1
(2650 2350);
PAINT ORANGE (2650 2350);
DISPLAY INVISIBLE (2650 2350);
FORCEPROP 2 LAST ROOM PROCHOT_MEMHOT_ISO
J 2
(2960 2380);
DISPLAY 0.978723 (2960 2380);
PAINT ORANGE (2960 2380);
DISPLAY INVISIBLE (2960 2380);
FORCEPROP 1 LAST OFFPAGE TRUE
J 2
(2325 2225);
PAINT GREEN (2325 2225);
DISPLAY INVISIBLE (2325 2225);
FORCEPROP 1 LAST COMMENT_BODY TRUE
J 2
(2550 2275);
DISPLAY 0.978723 (2550 2275);
PAINT GREEN (2550 2275);
DISPLAY INVISIBLE (2550 2275);
FORCEPROP 2 LAST PATH I70
J 0
(2945 2400);
DISPLAY 1.021277 (2945 2400);
PAINT ORANGE (2945 2400);
DISPLAY INVISIBLE (2945 2400);
FORCEADD OFFPAGE..5
R 2
(2650 1250);
FORCEPROP 2 LAST $XR0 55 
J 0
(2839 1250);
DISPLAY 0.638298 (2839 1250);
PAINT MONO (2839 1250);
FORCEPROP 2 LAST $XR1 95 
J 0
(2929 1250);
DISPLAY 0.638298 (2929 1250);
PAINT MONO (2929 1250);
FORCEPROP 2 LAST $XR2 152 
J 0
(3019 1250);
DISPLAY 0.638298 (3019 1250);
PAINT MONO (3019 1250);
FORCEPROP 2 LAST CDS_LIB mstr_standard
J 1
(2650 1250);
PAINT ORANGE (2650 1250);
DISPLAY INVISIBLE (2650 1250);
FORCEPROP 2 LAST ROOM PROCHOT_MEMHOT_ISO
J 2
(2960 1280);
DISPLAY 0.978723 (2960 1280);
PAINT ORANGE (2960 1280);
DISPLAY INVISIBLE (2960 1280);
FORCEPROP 1 LAST OFFPAGE TRUE
J 2
(2325 1125);
PAINT GREEN (2325 1125);
DISPLAY INVISIBLE (2325 1125);
FORCEPROP 1 LAST COMMENT_BODY TRUE
J 2
(2550 1175);
DISPLAY 0.978723 (2550 1175);
PAINT GREEN (2550 1175);
DISPLAY INVISIBLE (2550 1175);
FORCEPROP 2 LAST PATH I71
J 0
(2945 1300);
DISPLAY 1.021277 (2945 1300);
PAINT ORANGE (2945 1300);
DISPLAY INVISIBLE (2945 1300);
FORCEADD GND..1
(1900 1800);
FORCEPROP 3 LASTPIN (1900 1850) SIG_NAME GND\g
J 0
(1910 1860);
DISPLAY 0.659574 (1910 1860);
PAINT MONO (1910 1860);
DISPLAY INVISIBLE (1910 1860);
FORCEPROP 1 LAST VOLTAGE 0
J 0
(1900 1800);
PAINT SKYBLUE (1900 1800);
DISPLAY INVISIBLE (1900 1800);
FORCEPROP 2 LAST CDS_LIB mstr_symbols
J 0
(1900 1800);
PAINT ORANGE (1900 1800);
DISPLAY INVISIBLE (1900 1800);
FORCEPROP 1 LAST SIZE 1B
J 0
(1975 1750);
DISPLAY 1.170213 (1975 1750);
PAINT GREEN (1975 1750);
DISPLAY INVISIBLE (1975 1750);
FORCEPROP 1 LAST BODY_TYPE PLUMBING
J 0
(1855 1757);
DISPLAY 0.340426 (1855 1757);
PAINT GREEN (1855 1757);
DISPLAY INVISIBLE (1855 1757);
FORCEPROP 1 LAST PATH I74
J 0
(1975 1800);
DISPLAY 0.872340 (1975 1800);
PAINT AQUA (1975 1800);
DISPLAY INVISIBLE (1975 1800);
FORCEPROP 2 LAST ROOM PROCHOT_MEMHOT_ISO
J 0
(1525 1875);
PAINT ORANGE (1525 1875);
DISPLAY INVISIBLE (1525 1875);
FORCEPROP 1 LAST HDL_POWER GND
J 0
(1900 1950);
DISPLAY 1.170213 (1900 1950);
PAINT GREEN (1900 1950);
DISPLAY INVISIBLE (1900 1950);
FORCEADD FET_N_DUAL..5
(1900 2100);
FORCEPROP 1 LAST LOCATION Q7E2
J 0
(2050 1950);
DISPLAY 0.617021 (2050 1950);
PAINT AQUA (2050 1950);
FORCEPROP 1 LAST PART_NUMBER E40049-001
J 0
(2050 1800);
DISPLAY 0.617021 (2050 1800);
PAINT BLUE (2050 1800);
FORCEPROP 1 LAST VALUE NTJD4001N
J 0
(2050 1900);
DISPLAY 0.617021 (2050 1900);
PAINT SKYBLUE (2050 1900);
FORCEPROP 1 LAST MATERIAL FET
J 0
(2050 1850);
DISPLAY 0.617021 (2050 1850);
PAINT SKYBLUE (2050 1850);
FORCEPROP 1 LASTPIN (1900 1900) $PN 4
J 2
(1958 1900);
DISPLAY 0.617021 (1958 1900);
PAINT MONO (1958 1900);
FORCEPROP 1 LASTPIN (1700 2000) $PN 5
J 2
(1703 2015);
DISPLAY 0.617021 (1703 2015);
PAINT MONO (1703 2015);
FORCEPROP 1 LASTPIN (1900 2300) $PN 3
J 2
(1953 2265);
DISPLAY 0.617021 (1953 2265);
PAINT MONO (1953 2265);
FORCEPROP 1 LAST PACK_TYPE SMLF
J 0
(2100 1950);
PAINT SKYBLUE (2100 1950);
DISPLAY INVISIBLE (2100 1950);
FORCEPROP 2 LAST SEC_TYPE SMLF
J 0
(2100 2200);
DISPLAY 1.404255 (2100 2200);
PAINT ORANGE (2100 2200);
DISPLAY INVISIBLE (2100 2200);
FORCEPROP 2 LAST CDS_LIB mstr_discrete
J 0
(1900 2100);
PAINT ORANGE (1900 2100);
DISPLAY INVISIBLE (1900 2100);
FORCEPROP 2 LAST SEC 2
J 0
(2100 2200);
DISPLAY 0.936170 (2100 2200);
PAINT MONO (2100 2200);
DISPLAY INVISIBLE (2100 2200);
FORCEPROP 2 LAST CDS_LOCATION Q7E2
J 0
(2050 1950);
DISPLAY 0.617021 (2050 1950);
PAINT AQUA (2050 1950);
DISPLAY INVISIBLE (2050 1950);
FORCEPROP 1 LAST PATH I75
J 0
(2100 2150);
DISPLAY 0.978723 (2100 2150);
PAINT BLUE (2100 2150);
DISPLAY INVISIBLE (2100 2150);
FORCEPROP 2 LAST ROOM PROC_SIDEBAND
J 0
(1900 2140);
DISPLAY 0.787234 (1900 2140);
PAINT SKYBLUE (1900 2140);
DISPLAY INVISIBLE (1900 2140);
FORCEADD GND..1
(1900 700);
FORCEPROP 3 LASTPIN (1900 750) SIG_NAME GND\g
J 0
(1910 760);
DISPLAY 0.659574 (1910 760);
PAINT MONO (1910 760);
DISPLAY INVISIBLE (1910 760);
FORCEPROP 1 LAST VOLTAGE 0
J 0
(1900 700);
PAINT SKYBLUE (1900 700);
DISPLAY INVISIBLE (1900 700);
FORCEPROP 2 LAST CDS_LIB mstr_symbols
J 0
(1900 700);
PAINT ORANGE (1900 700);
DISPLAY INVISIBLE (1900 700);
FORCEPROP 1 LAST SIZE 1B
J 0
(1975 650);
DISPLAY 1.170213 (1975 650);
PAINT GREEN (1975 650);
DISPLAY INVISIBLE (1975 650);
FORCEPROP 1 LAST BODY_TYPE PLUMBING
J 0
(1855 657);
DISPLAY 0.340426 (1855 657);
PAINT GREEN (1855 657);
DISPLAY INVISIBLE (1855 657);
FORCEPROP 1 LAST PATH I76
J 0
(1975 700);
DISPLAY 0.872340 (1975 700);
PAINT AQUA (1975 700);
DISPLAY INVISIBLE (1975 700);
FORCEPROP 2 LAST ROOM PROCHOT_MEMHOT_ISO
J 0
(1525 775);
PAINT ORANGE (1525 775);
DISPLAY INVISIBLE (1525 775);
FORCEPROP 1 LAST HDL_POWER GND
J 0
(1900 850);
DISPLAY 1.170213 (1900 850);
PAINT GREEN (1900 850);
DISPLAY INVISIBLE (1900 850);
FORCEADD FET_N_DUAL..5
(1900 1000);
FORCEPROP 1 LAST LOCATION Q4B1
J 0
(2050 850);
DISPLAY 0.617021 (2050 850);
PAINT AQUA (2050 850);
FORCEPROP 1 LAST PART_NUMBER E40049-001
J 0
(2050 700);
DISPLAY 0.617021 (2050 700);
PAINT BLUE (2050 700);
FORCEPROP 1 LAST VALUE NTJD4001N
J 0
(2050 800);
DISPLAY 0.617021 (2050 800);
PAINT SKYBLUE (2050 800);
FORCEPROP 1 LAST MATERIAL FET
J 0
(2050 750);
DISPLAY 0.617021 (2050 750);
PAINT SKYBLUE (2050 750);
FORCEPROP 1 LASTPIN (1900 800) $PN 4
J 2
(1958 800);
DISPLAY 0.617021 (1958 800);
PAINT MONO (1958 800);
FORCEPROP 1 LASTPIN (1700 900) $PN 5
J 2
(1703 915);
DISPLAY 0.617021 (1703 915);
PAINT MONO (1703 915);
FORCEPROP 1 LASTPIN (1900 1200) $PN 3
J 2
(1953 1165);
DISPLAY 0.617021 (1953 1165);
PAINT MONO (1953 1165);
FORCEPROP 1 LAST PACK_TYPE SMLF
J 0
(2100 850);
PAINT SKYBLUE (2100 850);
DISPLAY INVISIBLE (2100 850);
FORCEPROP 2 LAST SEC_TYPE SMLF
J 0
(2100 1100);
DISPLAY 1.404255 (2100 1100);
PAINT ORANGE (2100 1100);
DISPLAY INVISIBLE (2100 1100);
FORCEPROP 2 LAST CDS_LIB mstr_discrete
J 0
(1900 1000);
PAINT ORANGE (1900 1000);
DISPLAY INVISIBLE (1900 1000);
FORCEPROP 2 LAST SEC 2
J 0
(2100 1100);
DISPLAY 0.936170 (2100 1100);
PAINT MONO (2100 1100);
DISPLAY INVISIBLE (2100 1100);
FORCEPROP 2 LAST CDS_LOCATION Q4B1
J 0
(2050 850);
DISPLAY 0.617021 (2050 850);
PAINT AQUA (2050 850);
DISPLAY INVISIBLE (2050 850);
FORCEPROP 1 LAST PATH I77
J 0
(2100 1050);
DISPLAY 0.978723 (2100 1050);
PAINT BLUE (2100 1050);
DISPLAY INVISIBLE (2100 1050);
FORCEPROP 2 LAST ROOM PROC_SIDEBAND
J 0
(1900 1040);
DISPLAY 0.787234 (1900 1040);
PAINT SKYBLUE (1900 1040);
DISPLAY INVISIBLE (1900 1040);
FORCEADD P3V3..1
(1175 2625);
FORCEPROP 3 LASTPIN (1175 2575) SIG_NAME P3V3\g
J 0
(1185 2585);
DISPLAY 0.659574 (1185 2585);
PAINT MONO (1185 2585);
DISPLAY INVISIBLE (1185 2585);
FORCEPROP 1 LAST VOLTAGE +3.3
J 0
(1175 2625);
PAINT SKYBLUE (1175 2625);
DISPLAY INVISIBLE (1175 2625);
FORCEPROP 2 LAST CDS_LIB mstr_symbols
J 0
(1175 2625);
PAINT ORANGE (1175 2625);
DISPLAY INVISIBLE (1175 2625);
FORCEPROP 1 LAST SIZE 1B
J 0
(1220 2647);
DISPLAY 0.553191 (1220 2647);
PAINT GREEN (1220 2647);
DISPLAY INVISIBLE (1220 2647);
FORCEPROP 1 LAST BODY_TYPE PLUMBING
J 0
(1130 2582);
DISPLAY 0.468085 (1130 2582);
PAINT GREEN (1130 2582);
DISPLAY INVISIBLE (1130 2582);
FORCEPROP 1 LAST PATH I78
J 0
(1220 2627);
DISPLAY 0.340426 (1220 2627);
PAINT GREEN (1220 2627);
DISPLAY INVISIBLE (1220 2627);
FORCEPROP 2 LAST ROOM PROCHOT_MEMHOT_ISO
J 0
(1025 2725);
PAINT PEACH (1025 2725);
DISPLAY INVISIBLE (1025 2725);
FORCEPROP 1 LAST HDL_POWER P3V3
J 0
(850 2500);
DISPLAY 1.170213 (850 2500);
PAINT GREEN (850 2500);
DISPLAY INVISIBLE (850 2500);
FORCEADD RES..2
R 2
(1175 2425);
FORCEPROP 1 LAST LOCATION R3R10
J 2
(1130 2500);
DISPLAY 0.617021 (1130 2500);
PAINT AQUA (1130 2500);
FORCEPROP 1 LAST PART_NUMBER G21796-072
R 1
J 0
(1235 2300);
DISPLAY 0.617021 (1235 2300);
PAINT BLUE (1235 2300);
FORCEPROP 1 LAST VALUE 4.75K
J 2
(1130 2450);
DISPLAY 0.617021 (1130 2450);
PAINT SKYBLUE (1130 2450);
FORCEPROP 1 LAST TOLERANCE 1%
J 2
(1130 2400);
DISPLAY 0.617021 (1130 2400);
PAINT SKYBLUE (1130 2400);
FORCEPROP 1 LAST PACK_TYPE 0402
J 2
(1135 2250);
DISPLAY 0.617021 (1135 2250);
PAINT SKYBLUE (1135 2250);
FORCEPROP 1 LAST MATERIAL CHIP
J 2
(1135 2300);
DISPLAY 0.617021 (1135 2300);
PAINT SKYBLUE (1135 2300);
FORCEPROP 1 LAST WATTAGE 1/16W
J 2
(1135 2350);
DISPLAY 0.617021 (1135 2350);
PAINT SKYBLUE (1135 2350);
FORCEPROP 1 LASTPIN (1175 2325) $PN 2
J 2
(1170 2335);
DISPLAY 0.617021 (1170 2335);
PAINT MONO (1170 2335);
FORCEPROP 1 LASTPIN (1175 2525) $PN 1
J 2
(1170 2487);
DISPLAY 0.617021 (1170 2487);
PAINT MONO (1170 2487);
FORCEPROP 2 LAST BOM_COST PROC_SIDEBAND
J 0
(1175 2425);
PAINT MONO (1175 2425);
DISPLAY INVISIBLE (1175 2425);
FORCEPROP 2 LAST CDS_LIB mstr_discrete
J 2
(1175 2425);
DISPLAY 1.361702 (1175 2425);
PAINT ORANGE (1175 2425);
DISPLAY INVISIBLE (1175 2425);
FORCEPROP 2 LAST CDS_SEC 1
J 1
(1125 2650);
DISPLAY 1.404255 (1125 2650);
PAINT ORANGE (1125 2650);
DISPLAY INVISIBLE (1125 2650);
FORCEPROP 2 LAST $SEC 1
J 1
(1125 2650);
DISPLAY 0.936170 (1125 2650);
PAINT MONO (1125 2650);
DISPLAY INVISIBLE (1125 2650);
FORCEPROP 2 LAST CDS_LOCATION R3R10
J 2
(1130 2500);
DISPLAY 0.617021 (1130 2500);
PAINT AQUA (1130 2500);
DISPLAY INVISIBLE (1130 2500);
FORCEPROP 1 LAST PATH I79
J 2
(1125 2600);
DISPLAY 0.978723 (1125 2600);
PAINT WHITE (1125 2600);
DISPLAY INVISIBLE (1125 2600);
FORCEPROP 2 LAST ROOM PROC_SIDEBAND
J 2
(1125 2600);
PAINT PEACH (1125 2600);
DISPLAY INVISIBLE (1125 2600);
FORCEADD GND..1
(1175 1700);
FORCEPROP 3 LASTPIN (1175 1750) SIG_NAME GND\g
J 0
(1185 1760);
DISPLAY 0.659574 (1185 1760);
PAINT MONO (1185 1760);
DISPLAY INVISIBLE (1185 1760);
FORCEPROP 1 LAST VOLTAGE 0
J 0
(1175 1700);
PAINT SKYBLUE (1175 1700);
DISPLAY INVISIBLE (1175 1700);
FORCEPROP 2 LAST CDS_LIB mstr_symbols
J 0
(1175 1700);
PAINT ORANGE (1175 1700);
DISPLAY INVISIBLE (1175 1700);
FORCEPROP 1 LAST SIZE 1B
J 0
(1250 1650);
DISPLAY 1.170213 (1250 1650);
PAINT GREEN (1250 1650);
DISPLAY INVISIBLE (1250 1650);
FORCEPROP 1 LAST BODY_TYPE PLUMBING
J 0
(1130 1657);
DISPLAY 0.340426 (1130 1657);
PAINT GREEN (1130 1657);
DISPLAY INVISIBLE (1130 1657);
FORCEPROP 1 LAST PATH I80
J 0
(1250 1700);
DISPLAY 0.872340 (1250 1700);
PAINT AQUA (1250 1700);
DISPLAY INVISIBLE (1250 1700);
FORCEPROP 2 LAST ROOM PROCHOT_MEMHOT_ISO
J 0
(800 1775);
PAINT ORANGE (800 1775);
DISPLAY INVISIBLE (800 1775);
FORCEPROP 1 LAST HDL_POWER GND
J 0
(1175 1850);
DISPLAY 1.170213 (1175 1850);
PAINT GREEN (1175 1850);
DISPLAY INVISIBLE (1175 1850);
FORCEADD P3V3..1
(1175 1525);
FORCEPROP 3 LASTPIN (1175 1475) SIG_NAME P3V3\g
J 0
(1185 1485);
DISPLAY 0.659574 (1185 1485);
PAINT MONO (1185 1485);
DISPLAY INVISIBLE (1185 1485);
FORCEPROP 1 LAST VOLTAGE +3.3
J 0
(1175 1525);
PAINT SKYBLUE (1175 1525);
DISPLAY INVISIBLE (1175 1525);
FORCEPROP 2 LAST CDS_LIB mstr_symbols
J 0
(1175 1525);
PAINT ORANGE (1175 1525);
DISPLAY INVISIBLE (1175 1525);
FORCEPROP 1 LAST SIZE 1B
J 0
(1220 1547);
DISPLAY 0.553191 (1220 1547);
PAINT GREEN (1220 1547);
DISPLAY INVISIBLE (1220 1547);
FORCEPROP 1 LAST BODY_TYPE PLUMBING
J 0
(1130 1482);
DISPLAY 0.468085 (1130 1482);
PAINT GREEN (1130 1482);
DISPLAY INVISIBLE (1130 1482);
FORCEPROP 1 LAST PATH I81
J 0
(1220 1527);
DISPLAY 0.340426 (1220 1527);
PAINT GREEN (1220 1527);
DISPLAY INVISIBLE (1220 1527);
FORCEPROP 2 LAST ROOM PROCHOT_MEMHOT_ISO
J 0
(1025 1625);
PAINT PEACH (1025 1625);
DISPLAY INVISIBLE (1025 1625);
FORCEPROP 1 LAST HDL_POWER P3V3
J 0
(850 1400);
DISPLAY 1.170213 (850 1400);
PAINT GREEN (850 1400);
DISPLAY INVISIBLE (850 1400);
FORCEADD RES..2
R 2
(1175 1325);
FORCEPROP 1 LAST LOCATION R6M4
J 2
(1130 1400);
DISPLAY 0.617021 (1130 1400);
PAINT AQUA (1130 1400);
FORCEPROP 1 LAST PART_NUMBER G21796-072
R 1
J 0
(1235 1200);
DISPLAY 0.617021 (1235 1200);
PAINT BLUE (1235 1200);
FORCEPROP 1 LAST VALUE 4.75K
J 2
(1130 1350);
DISPLAY 0.617021 (1130 1350);
PAINT SKYBLUE (1130 1350);
FORCEPROP 1 LAST TOLERANCE 1%
J 2
(1130 1300);
DISPLAY 0.617021 (1130 1300);
PAINT SKYBLUE (1130 1300);
FORCEPROP 1 LAST PACK_TYPE 0402
J 2
(1135 1150);
DISPLAY 0.617021 (1135 1150);
PAINT SKYBLUE (1135 1150);
FORCEPROP 1 LAST MATERIAL CHIP
J 2
(1135 1200);
DISPLAY 0.617021 (1135 1200);
PAINT SKYBLUE (1135 1200);
FORCEPROP 1 LAST WATTAGE 1/16W
J 2
(1135 1250);
DISPLAY 0.617021 (1135 1250);
PAINT SKYBLUE (1135 1250);
FORCEPROP 1 LASTPIN (1175 1225) $PN 2
J 2
(1170 1235);
DISPLAY 0.617021 (1170 1235);
PAINT MONO (1170 1235);
FORCEPROP 1 LASTPIN (1175 1425) $PN 1
J 2
(1170 1387);
DISPLAY 0.617021 (1170 1387);
PAINT MONO (1170 1387);
FORCEPROP 2 LAST BOM_COST PROC_SIDEBAND
J 0
(1175 1325);
PAINT MONO (1175 1325);
DISPLAY INVISIBLE (1175 1325);
FORCEPROP 2 LAST CDS_LIB mstr_discrete
J 2
(1175 1325);
DISPLAY 1.361702 (1175 1325);
PAINT ORANGE (1175 1325);
DISPLAY INVISIBLE (1175 1325);
FORCEPROP 2 LAST CDS_SEC 1
J 1
(1125 1550);
DISPLAY 1.404255 (1125 1550);
PAINT ORANGE (1125 1550);
DISPLAY INVISIBLE (1125 1550);
FORCEPROP 2 LAST $SEC 1
J 1
(1125 1550);
DISPLAY 0.936170 (1125 1550);
PAINT MONO (1125 1550);
DISPLAY INVISIBLE (1125 1550);
FORCEPROP 2 LAST CDS_LOCATION R6M4
J 2
(1130 1400);
DISPLAY 0.617021 (1130 1400);
PAINT AQUA (1130 1400);
DISPLAY INVISIBLE (1130 1400);
FORCEPROP 1 LAST PATH I82
J 2
(1125 1500);
DISPLAY 0.978723 (1125 1500);
PAINT WHITE (1125 1500);
DISPLAY INVISIBLE (1125 1500);
FORCEPROP 2 LAST ROOM PROC_SIDEBAND
J 2
(1125 1500);
PAINT PEACH (1125 1500);
DISPLAY INVISIBLE (1125 1500);
FORCEADD GND..1
(1175 600);
FORCEPROP 3 LASTPIN (1175 650) SIG_NAME GND\g
J 0
(1185 660);
DISPLAY 0.659574 (1185 660);
PAINT MONO (1185 660);
DISPLAY INVISIBLE (1185 660);
FORCEPROP 1 LAST VOLTAGE 0
J 0
(1175 600);
PAINT SKYBLUE (1175 600);
DISPLAY INVISIBLE (1175 600);
FORCEPROP 2 LAST CDS_LIB mstr_symbols
J 0
(1175 600);
PAINT ORANGE (1175 600);
DISPLAY INVISIBLE (1175 600);
FORCEPROP 1 LAST SIZE 1B
J 0
(1250 550);
DISPLAY 1.170213 (1250 550);
PAINT GREEN (1250 550);
DISPLAY INVISIBLE (1250 550);
FORCEPROP 1 LAST BODY_TYPE PLUMBING
J 0
(1130 557);
DISPLAY 0.340426 (1130 557);
PAINT GREEN (1130 557);
DISPLAY INVISIBLE (1130 557);
FORCEPROP 1 LAST PATH I83
J 0
(1250 600);
DISPLAY 0.872340 (1250 600);
PAINT AQUA (1250 600);
DISPLAY INVISIBLE (1250 600);
FORCEPROP 2 LAST ROOM PROCHOT_MEMHOT_ISO
J 0
(800 675);
PAINT ORANGE (800 675);
DISPLAY INVISIBLE (800 675);
FORCEPROP 1 LAST HDL_POWER GND
J 0
(1175 750);
DISPLAY 1.170213 (1175 750);
PAINT GREEN (1175 750);
DISPLAY INVISIBLE (1175 750);
FORCEADD FET_N_DUAL..5
(1175 875);
FORCEPROP 1 LAST LOCATION Q4B1
J 0
(1300 700);
DISPLAY 0.617021 (1300 700);
PAINT AQUA (1300 700);
FORCEPROP 1 LAST PART_NUMBER E40049-001
J 0
(1300 550);
DISPLAY 0.617021 (1300 550);
PAINT BLUE (1300 550);
FORCEPROP 1 LAST VALUE NTJD4001N
J 0
(1300 650);
DISPLAY 0.617021 (1300 650);
PAINT SKYBLUE (1300 650);
FORCEPROP 1 LAST MATERIAL FET
J 0
(1300 600);
DISPLAY 0.617021 (1300 600);
PAINT SKYBLUE (1300 600);
FORCEPROP 1 LASTPIN (1175 675) $PN 1
J 2
(1233 675);
DISPLAY 0.617021 (1233 675);
PAINT MONO (1233 675);
FORCEPROP 1 LASTPIN (975 775) $PN 2
J 2
(978 790);
DISPLAY 0.617021 (978 790);
PAINT MONO (978 790);
FORCEPROP 1 LASTPIN (1175 1075) $PN 6
J 2
(1228 1040);
DISPLAY 0.617021 (1228 1040);
PAINT MONO (1228 1040);
FORCEPROP 1 LAST PACK_TYPE SMLF
J 0
(1375 725);
PAINT SKYBLUE (1375 725);
DISPLAY INVISIBLE (1375 725);
FORCEPROP 2 LAST SEC_TYPE SMLF
J 0
(1375 975);
DISPLAY 1.404255 (1375 975);
PAINT ORANGE (1375 975);
DISPLAY INVISIBLE (1375 975);
FORCEPROP 2 LAST CDS_LIB mstr_discrete
J 0
(1175 875);
PAINT ORANGE (1175 875);
DISPLAY INVISIBLE (1175 875);
FORCEPROP 2 LAST SEC 1
J 0
(1375 975);
DISPLAY 0.936170 (1375 975);
PAINT MONO (1375 975);
DISPLAY INVISIBLE (1375 975);
FORCEPROP 2 LAST CDS_LOCATION Q4B1
J 0
(1300 700);
DISPLAY 0.617021 (1300 700);
PAINT AQUA (1300 700);
DISPLAY INVISIBLE (1300 700);
FORCEPROP 1 LAST PATH I84
J 0
(1375 925);
DISPLAY 0.978723 (1375 925);
PAINT BLUE (1375 925);
DISPLAY INVISIBLE (1375 925);
FORCEPROP 2 LAST ROOM PROC_SIDEBAND
J 0
(1175 915);
DISPLAY 0.787234 (1175 915);
PAINT SKYBLUE (1175 915);
DISPLAY INVISIBLE (1175 915);
FORCEADD OFFPAGE..1
(0 1875);
FORCEPROP 2 LAST $XR0 223 
J 0
(-282 1875);
DISPLAY 0.638298 (-282 1875);
PAINT MONO (-282 1875);
FORCEPROP 2 LAST $XR1 119 
J 0
(-402 1875);
DISPLAY 0.638298 (-402 1875);
PAINT MONO (-402 1875);
FORCEPROP 2 LAST $XR2 144 
J 0
(-522 1875);
DISPLAY 0.638298 (-522 1875);
PAINT MONO (-522 1875);
FORCEPROP 2 LAST ROOM PROCHOT_MEMHOT_ISO
J 0
(-250 1925);
DISPLAY 0.978723 (-250 1925);
PAINT ORANGE (-250 1925);
DISPLAY INVISIBLE (-250 1925);
FORCEPROP 2 LAST CDS_LIB mstr_standard
J 0
(0 1875);
PAINT ORANGE (0 1875);
DISPLAY INVISIBLE (0 1875);
FORCEPROP 1 LAST OFFPAGE TRUE
J 0
(325 1750);
PAINT GREEN (325 1750);
DISPLAY INVISIBLE (325 1750);
FORCEPROP 1 LAST COMMENT_BODY TRUE
J 0
(125 1775);
DISPLAY 0.978723 (125 1775);
PAINT PEACH (125 1775);
DISPLAY INVISIBLE (125 1775);
FORCEPROP 2 LAST PATH I85
J 0
(-250 1925);
DISPLAY 1.021277 (-250 1925);
PAINT ORANGE (-250 1925);
DISPLAY INVISIBLE (-250 1925);
FORCEADD OFFPAGE..1
(0 775);
FORCEPROP 2 LAST $XR0 226 
J 0
(-282 775);
DISPLAY 0.638298 (-282 775);
PAINT MONO (-282 775);
FORCEPROP 2 LAST $XR1 119 
J 0
(-402 775);
DISPLAY 0.638298 (-402 775);
PAINT MONO (-402 775);
FORCEPROP 2 LAST $XR2 145 
J 0
(-522 775);
DISPLAY 0.638298 (-522 775);
PAINT MONO (-522 775);
FORCEPROP 2 LAST ROOM PROCHOT_MEMHOT_ISO
J 0
(-250 825);
DISPLAY 0.978723 (-250 825);
PAINT ORANGE (-250 825);
DISPLAY INVISIBLE (-250 825);
FORCEPROP 2 LAST CDS_LIB mstr_standard
J 0
(0 775);
PAINT ORANGE (0 775);
DISPLAY INVISIBLE (0 775);
FORCEPROP 1 LAST OFFPAGE TRUE
J 0
(325 650);
PAINT GREEN (325 650);
DISPLAY INVISIBLE (325 650);
FORCEPROP 1 LAST COMMENT_BODY TRUE
J 0
(125 675);
DISPLAY 0.978723 (125 675);
PAINT PEACH (125 675);
DISPLAY INVISIBLE (125 675);
FORCEPROP 2 LAST PATH I86
J 0
(-250 825);
DISPLAY 1.021277 (-250 825);
PAINT ORANGE (-250 825);
DISPLAY INVISIBLE (-250 825);
FORCEADD FET_N_DUAL..5
(-1425 2050);
FORCEPROP 1 LAST LOCATION Q3U1
J 0
(-1225 2050);
DISPLAY 0.617021 (-1225 2050);
PAINT AQUA (-1225 2050);
FORCEPROP 1 LAST PART_NUMBER E40049-001
J 0
(-1300 1725);
DISPLAY 0.617021 (-1300 1725);
PAINT BLUE (-1300 1725);
FORCEPROP 1 LAST VALUE NTJD4001N
J 0
(-1300 1825);
DISPLAY 0.617021 (-1300 1825);
PAINT SKYBLUE (-1300 1825);
FORCEPROP 1 LAST MATERIAL FET
J 0
(-1300 1775);
DISPLAY 0.617021 (-1300 1775);
PAINT SKYBLUE (-1300 1775);
FORCEPROP 1 LASTPIN (-1425 1850) $PN 4
J 2
(-1367 1850);
DISPLAY 0.617021 (-1367 1850);
PAINT WHITE (-1367 1850);
FORCEPROP 1 LASTPIN (-1625 1950) $PN 5
J 2
(-1622 1965);
DISPLAY 0.617021 (-1622 1965);
PAINT WHITE (-1622 1965);
FORCEPROP 1 LASTPIN (-1425 2250) $PN 3
J 2
(-1372 2215);
DISPLAY 0.617021 (-1372 2215);
PAINT WHITE (-1372 2215);
FORCEPROP 1 LAST PACK_TYPE SMLF
J 0
(-1225 1900);
PAINT SKYBLUE (-1225 1900);
DISPLAY INVISIBLE (-1225 1900);
FORCEPROP 2 LAST SEC_TYPE SMLF
J 0
(-1225 2150);
DISPLAY 1.021277 (-1225 2150);
PAINT ORANGE (-1225 2150);
DISPLAY INVISIBLE (-1225 2150);
FORCEPROP 2 LAST CDS_LIB mstr_discrete
J 0
(-1425 2050);
PAINT ORANGE (-1425 2050);
DISPLAY INVISIBLE (-1425 2050);
FORCEPROP 2 LAST SEC 2
J 0
(-1225 2150);
DISPLAY 0.680851 (-1225 2150);
PAINT MONO (-1225 2150);
DISPLAY INVISIBLE (-1225 2150);
FORCEPROP 2 LAST CDS_LOCATION Q3U1
J 0
(-1225 2050);
DISPLAY 0.617021 (-1225 2050);
PAINT AQUA (-1225 2050);
DISPLAY INVISIBLE (-1225 2050);
FORCEPROP 1 LAST PATH I89
J 0
(-1225 2100);
DISPLAY 0.978723 (-1225 2100);
PAINT BLUE (-1225 2100);
DISPLAY INVISIBLE (-1225 2100);
FORCEPROP 2 LAST ROOM PROC_SIDEBAND
J 0
(-1425 2090);
DISPLAY 0.787234 (-1425 2090);
PAINT SKYBLUE (-1425 2090);
DISPLAY INVISIBLE (-1425 2090);
FORCEADD OFFPAGE..2
(2450 4250);
FORCEPROP 2 LAST $XR0 156 
J 0
(2639 4250);
DISPLAY 0.638298 (2639 4250);
PAINT MONO (2639 4250);
FORCEPROP 2 LAST $XR1 191 
J 0
(2759 4250);
DISPLAY 0.638298 (2759 4250);
PAINT MONO (2759 4250);
FORCEPROP 2 LAST CDS_LIB mstr_standard
J 1
(2450 4250);
PAINT ORANGE (2450 4250);
DISPLAY INVISIBLE (2450 4250);
FORCEPROP 2 LAST ROOM DIMM_EVENT
J 0
(2650 4300);
PAINT MONO (2650 4300);
DISPLAY INVISIBLE (2650 4300);
FORCEPROP 1 LAST OFFPAGE TRUE
J 0
(2775 4125);
PAINT GREEN (2775 4125);
DISPLAY INVISIBLE (2775 4125);
FORCEPROP 1 LAST COMMENT_BODY TRUE
J 0
(2405 4155);
DISPLAY 1.170213 (2405 4155);
PAINT GREEN (2405 4155);
DISPLAY INVISIBLE (2405 4155);
FORCEPROP 2 LAST PATH I90
J 0
(3000 4300);
DISPLAY 1.021277 (3000 4300);
PAINT ORANGE (3000 4300);
DISPLAY INVISIBLE (3000 4300);
FORCEADD RES..2
R 2
(1400 4400);
FORCEPROP 1 LAST LOCATION R4U1
J 2
(1355 4525);
DISPLAY 0.617021 (1355 4525);
PAINT AQUA (1355 4525);
FORCEPROP 1 LAST PART_NUMBER G21796-072
J 2
(1360 4325);
DISPLAY 0.617021 (1360 4325);
PAINT BLUE (1360 4325);
FORCEPROP 1 LAST VALUE 4.75K
J 2
(1355 4475);
DISPLAY 0.617021 (1355 4475);
PAINT SKYBLUE (1355 4475);
FORCEPROP 1 LAST TOLERANCE 1%
J 2
(1355 4425);
DISPLAY 0.617021 (1355 4425);
PAINT SKYBLUE (1355 4425);
FORCEPROP 1 LAST PACK_TYPE 0402
J 2
(1385 4225);
DISPLAY 0.617021 (1385 4225);
PAINT SKYBLUE (1385 4225);
FORCEPROP 1 LAST MATERIAL CHIP
J 2
(1360 4275);
DISPLAY 0.617021 (1360 4275);
PAINT SKYBLUE (1360 4275);
FORCEPROP 1 LAST WATTAGE 1/16W
J 2
(1360 4375);
DISPLAY 0.617021 (1360 4375);
PAINT SKYBLUE (1360 4375);
FORCEPROP 1 LASTPIN (1400 4300) $PN 2
J 2
(1395 4310);
DISPLAY 0.617021 (1395 4310);
PAINT MONO (1395 4310);
FORCEPROP 1 LASTPIN (1400 4500) $PN 1
J 2
(1395 4462);
DISPLAY 0.617021 (1395 4462);
PAINT MONO (1395 4462);
FORCEPROP 2 LAST BOM_COST PROC_SIDEBAND
J 2
(1400 4400);
PAINT MONO (1400 4400);
DISPLAY INVISIBLE (1400 4400);
FORCEPROP 2 LAST CDS_LIB mstr_discrete
J 2
(1400 4400);
PAINT ORANGE (1400 4400);
DISPLAY INVISIBLE (1400 4400);
FORCEPROP 2 LAST SEC_TYPE 0402
J 0
(1350 4625);
DISPLAY 1.021277 (1350 4625);
PAINT ORANGE (1350 4625);
DISPLAY INVISIBLE (1350 4625);
FORCEPROP 2 LAST SEC 1
J 0
(1350 4625);
DISPLAY 0.680851 (1350 4625);
PAINT MONO (1350 4625);
DISPLAY INVISIBLE (1350 4625);
FORCEPROP 2 LAST CDS_LOCATION R4U1
J 2
(1355 4525);
DISPLAY 0.617021 (1355 4525);
PAINT AQUA (1355 4525);
DISPLAY INVISIBLE (1355 4525);
FORCEPROP 1 LAST PATH I91
J 2
(1350 4575);
DISPLAY 0.978723 (1350 4575);
PAINT WHITE (1350 4575);
DISPLAY INVISIBLE (1350 4575);
FORCEPROP 2 LAST ROOM PROC_SIDEBAND
J 2
(1375 4175);
PAINT ORANGE (1375 4175);
DISPLAY INVISIBLE (1375 4175);
FORCEADD P3V3_STBY..1
(1400 4700);
FORCEPROP 3 LASTPIN (1400 4650) SIG_NAME P3V3_STBY\g
J 0
(1410 4660);
DISPLAY 0.659574 (1410 4660);
PAINT MONO (1410 4660);
DISPLAY INVISIBLE (1410 4660);
FORCEPROP 1 LAST VOLTAGE 3.3V
J 0
(1355 4657);
DISPLAY 0.340426 (1355 4657);
PAINT SKYBLUE (1355 4657);
DISPLAY INVISIBLE (1355 4657);
FORCEPROP 1 LAST SIZE 1B
J 0
(1445 4722);
DISPLAY 0.340426 (1445 4722);
PAINT GREEN (1445 4722);
DISPLAY INVISIBLE (1445 4722);
FORCEPROP 2 LAST CDS_LIB mstr_symbols
J 0
(1400 4700);
PAINT ORANGE (1400 4700);
DISPLAY INVISIBLE (1400 4700);
FORCEPROP 1 LAST BODY_TYPE PLUMBING
J 0
(1355 4657);
DISPLAY 0.340426 (1355 4657);
PAINT GREEN (1355 4657);
DISPLAY INVISIBLE (1355 4657);
FORCEPROP 1 LAST PATH I92
J 0
(1445 4702);
DISPLAY 0.340426 (1445 4702);
PAINT GREEN (1445 4702);
DISPLAY INVISIBLE (1445 4702);
FORCEPROP 1 LAST HDL_POWER P3V3_STBY
J 0
(1100 4575);
DISPLAY 0.872340 (1100 4575);
PAINT ORANGE (1100 4575);
DISPLAY INVISIBLE (1100 4575);
FORCEADD RES..2
R 2
(175 4075);
FORCEPROP 1 LAST LOCATION R4U3
J 2
(130 4200);
DISPLAY 0.617021 (130 4200);
PAINT AQUA (130 4200);
FORCEPROP 1 LAST PART_NUMBER G21796-072
J 2
(135 4000);
DISPLAY 0.617021 (135 4000);
PAINT BLUE (135 4000);
FORCEPROP 1 LAST VALUE 4.75K
J 2
(130 4150);
DISPLAY 0.617021 (130 4150);
PAINT SKYBLUE (130 4150);
FORCEPROP 1 LAST TOLERANCE 1%
J 2
(130 4100);
DISPLAY 0.617021 (130 4100);
PAINT SKYBLUE (130 4100);
FORCEPROP 1 LAST PACK_TYPE 0402
J 2
(135 3900);
DISPLAY 0.617021 (135 3900);
PAINT SKYBLUE (135 3900);
FORCEPROP 1 LAST MATERIAL CHIP
J 2
(135 3950);
DISPLAY 0.617021 (135 3950);
PAINT SKYBLUE (135 3950);
FORCEPROP 1 LAST WATTAGE 1/16W
J 2
(135 4050);
DISPLAY 0.617021 (135 4050);
PAINT SKYBLUE (135 4050);
FORCEPROP 1 LASTPIN (175 3975) $PN 2
J 2
(170 3985);
DISPLAY 0.617021 (170 3985);
PAINT MONO (170 3985);
FORCEPROP 1 LASTPIN (175 4175) $PN 1
J 2
(170 4137);
DISPLAY 0.617021 (170 4137);
PAINT MONO (170 4137);
FORCEPROP 2 LAST SEC_TYPE 0402
J 0
(125 4300);
DISPLAY 1.021277 (125 4300);
PAINT ORANGE (125 4300);
DISPLAY INVISIBLE (125 4300);
FORCEPROP 2 LAST BOM_COST PROC_SIDEBAND
J 2
(175 4075);
PAINT MONO (175 4075);
DISPLAY INVISIBLE (175 4075);
FORCEPROP 2 LAST CDS_LIB mstr_discrete
J 2
(175 4075);
PAINT ORANGE (175 4075);
DISPLAY INVISIBLE (175 4075);
FORCEPROP 2 LAST SEC 1
J 0
(125 4300);
DISPLAY 0.680851 (125 4300);
PAINT MONO (125 4300);
DISPLAY INVISIBLE (125 4300);
FORCEPROP 2 LAST CDS_LOCATION R4U3
J 2
(130 4200);
DISPLAY 0.617021 (130 4200);
PAINT AQUA (130 4200);
DISPLAY INVISIBLE (130 4200);
FORCEPROP 1 LAST PATH I94
J 2
(125 4250);
DISPLAY 0.978723 (125 4250);
PAINT WHITE (125 4250);
DISPLAY INVISIBLE (125 4250);
FORCEPROP 2 LAST ROOM PROC_SIDEBAND
J 2
(150 3850);
PAINT ORANGE (150 3850);
DISPLAY INVISIBLE (150 3850);
FORCEADD GND..1
(1400 3550);
FORCEPROP 3 LASTPIN (1400 3600) SIG_NAME GND\g
J 0
(1410 3610);
DISPLAY 0.659574 (1410 3610);
PAINT MONO (1410 3610);
DISPLAY INVISIBLE (1410 3610);
FORCEPROP 1 LAST VOLTAGE 0
J 0
(1400 3550);
PAINT SKYBLUE (1400 3550);
DISPLAY INVISIBLE (1400 3550);
FORCEPROP 2 LAST CDS_LIB mstr_symbols
J 0
(1400 3550);
DISPLAY 1.765957 (1400 3550);
PAINT ORANGE (1400 3550);
DISPLAY INVISIBLE (1400 3550);
FORCEPROP 1 LAST SIZE 1B
J 0
(1475 3500);
DISPLAY 0.978723 (1475 3500);
PAINT GREEN (1475 3500);
DISPLAY INVISIBLE (1475 3500);
FORCEPROP 2 LAST BOM_COST DEBUG
J 0
(1250 3625);
PAINT MONO (1250 3625);
DISPLAY INVISIBLE (1250 3625);
FORCEPROP 1 LAST BODY_TYPE PLUMBING
J 0
(1355 3507);
DISPLAY 0.340426 (1355 3507);
PAINT GREEN (1355 3507);
DISPLAY INVISIBLE (1355 3507);
FORCEPROP 1 LAST PATH I95
J 0
(1475 3550);
DISPLAY 0.872340 (1475 3550);
PAINT AQUA (1475 3550);
DISPLAY INVISIBLE (1475 3550);
FORCEPROP 2 LAST ROOM SYSTEM_DEBUG_LEDS
J 0
(1050 3625);
DISPLAY 0.978723 (1050 3625);
PAINT ORANGE (1050 3625);
DISPLAY INVISIBLE (1050 3625);
FORCEPROP 1 LAST HDL_POWER GND
J 0
(1400 3700);
DISPLAY 0.978723 (1400 3700);
PAINT GREEN (1400 3700);
DISPLAY INVISIBLE (1400 3700);
FORCEADD GND..1
(175 3225);
FORCEPROP 3 LASTPIN (175 3275) SIG_NAME GND\g
J 0
(185 3285);
DISPLAY 0.659574 (185 3285);
PAINT MONO (185 3285);
DISPLAY INVISIBLE (185 3285);
FORCEPROP 1 LAST VOLTAGE 0
J 0
(175 3225);
PAINT SKYBLUE (175 3225);
DISPLAY INVISIBLE (175 3225);
FORCEPROP 1 LAST SIZE 1B
J 0
(250 3175);
DISPLAY 1.170213 (250 3175);
PAINT GREEN (250 3175);
DISPLAY INVISIBLE (250 3175);
FORCEPROP 2 LAST CDS_LIB mstr_symbols
J 0
(175 3225);
PAINT MONO (175 3225);
DISPLAY INVISIBLE (175 3225);
FORCEPROP 1 LAST BODY_TYPE PLUMBING
J 0
(130 3182);
DISPLAY 0.340426 (130 3182);
PAINT GREEN (130 3182);
DISPLAY INVISIBLE (130 3182);
FORCEPROP 1 LAST PATH I97
J 0
(250 3225);
DISPLAY 0.872340 (250 3225);
PAINT AQUA (250 3225);
DISPLAY INVISIBLE (250 3225);
FORCEPROP 1 LAST HDL_POWER GND
J 0
(175 3375);
DISPLAY 1.170213 (175 3375);
PAINT GREEN (175 3375);
DISPLAY INVISIBLE (175 3375);
FORCEADD FET_N_DUAL..5
(175 3525);
FORCEPROP 1 LAST LOCATION Q4U1
J 0
(375 3525);
DISPLAY 0.617021 (375 3525);
PAINT AQUA (375 3525);
FORCEPROP 1 LAST PART_NUMBER E40049-001
J 0
(-225 3725);
DISPLAY 0.617021 (-225 3725);
PAINT BLUE (-225 3725);
FORCEPROP 1 LAST VALUE NTJD4001N
J 0
(-225 3675);
DISPLAY 0.617021 (-225 3675);
PAINT SKYBLUE (-225 3675);
FORCEPROP 1 LAST MATERIAL FET
J 0
(-225 3625);
DISPLAY 0.617021 (-225 3625);
PAINT SKYBLUE (-225 3625);
FORCEPROP 1 LASTPIN (175 3325) $PN 1
J 2
(233 3325);
DISPLAY 0.617021 (233 3325);
PAINT WHITE (233 3325);
FORCEPROP 1 LASTPIN (-25 3425) $PN 2
J 2
(-22 3440);
DISPLAY 0.617021 (-22 3440);
PAINT WHITE (-22 3440);
FORCEPROP 1 LASTPIN (175 3725) $PN 6
J 2
(228 3690);
DISPLAY 0.617021 (228 3690);
PAINT WHITE (228 3690);
FORCEPROP 1 LAST PACK_TYPE SMLF
J 0
(375 3375);
PAINT SKYBLUE (375 3375);
DISPLAY INVISIBLE (375 3375);
FORCEPROP 2 LAST CDS_LIB mstr_discrete
J 0
(175 3525);
PAINT ORANGE (175 3525);
DISPLAY INVISIBLE (175 3525);
FORCEPROP 2 LAST SEC_TYPE SMLF
J 0
(-225 3775);
DISPLAY 1.021277 (-225 3775);
PAINT ORANGE (-225 3775);
DISPLAY INVISIBLE (-225 3775);
FORCEPROP 2 LAST BOM_COST PROC_SIDEBAND
J 0
(175 3525);
PAINT MONO (175 3525);
DISPLAY INVISIBLE (175 3525);
FORCEPROP 2 LAST SEC 1
J 0
(-225 3775);
DISPLAY 0.680851 (-225 3775);
PAINT MONO (-225 3775);
DISPLAY INVISIBLE (-225 3775);
FORCEPROP 2 LAST CDS_LOCATION Q4U1
J 0
(375 3525);
DISPLAY 0.617021 (375 3525);
PAINT AQUA (375 3525);
DISPLAY INVISIBLE (375 3525);
FORCEPROP 1 LAST PATH I98
J 0
(375 3575);
DISPLAY 0.978723 (375 3575);
PAINT BLUE (375 3575);
DISPLAY INVISIBLE (375 3575);
FORCEPROP 2 LAST ROOM PROC_SIDEBAND
J 0
(375 3625);
PAINT ORANGE (375 3625);
DISPLAY INVISIBLE (375 3625);
FORCEADD PVPP_ABC..1
(-300 4050);
FORCEPROP 3 LASTPIN (-300 4000) SIG_NAME PVPP_ABC\g
J 0
(-290 4010);
DISPLAY 0.659574 (-290 4010);
PAINT MONO (-290 4010);
DISPLAY INVISIBLE (-290 4010);
FORCEPROP 1 LAST VOLTAGE 2.5V
J 0
(-345 4007);
DISPLAY 0.340426 (-345 4007);
PAINT SKYBLUE (-345 4007);
DISPLAY INVISIBLE (-345 4007);
FORCEPROP 2 LAST BOM_COST PVPP_KLM_VR
J 0
(-225 4150);
PAINT MONO (-225 4150);
DISPLAY INVISIBLE (-225 4150);
FORCEPROP 2 LAST CDS_LIB mstr_symbols
J 0
(-300 4050);
PAINT ORANGE (-300 4050);
DISPLAY INVISIBLE (-300 4050);
FORCEPROP 1 LAST BODY_TYPE PLUMBING
J 0
(-345 4007);
DISPLAY 0.340426 (-345 4007);
PAINT GREEN (-345 4007);
DISPLAY INVISIBLE (-345 4007);
FORCEPROP 1 LAST PATH I99
J 0
(-250 4075);
DISPLAY 0.872340 (-250 4075);
PAINT AQUA (-250 4075);
DISPLAY INVISIBLE (-250 4075);
FORCEPROP 2 LAST ROOM PVPP_KLM_VR
J 0
(-50 4150);
PAINT ORANGE (-50 4150);
DISPLAY INVISIBLE (-50 4150);
FORCEPROP 1 LAST HDL_POWER PVPP_ABC
J 1
(-300 4100);
DISPLAY 0.872340 (-300 4100);
PAINT GREEN (-300 4100);
DISPLAY INVISIBLE (-300 4100);
FORCEADD INTEL_CORP_BPAGE..1
(4250 25);
FORCEPROP 1 LAST CDS_CON_LAST_MODIFIED Tue Dec 01 11:51:48 2015
J 0
(2825 350);
PAINT ORANGE (2825 350);
DISPLAY INVISIBLE (2825 350);
FORCEPROP 1 LAST CUSTOM_TXT_CDS <CURRENT_DESIGN_SHEET> OF <TOTAL_DESIGN_SHEETS>
J 0
(3750 50);
PAINT GREEN (3750 50);
FORCEPROP 1 LAST CUSTOM_TXT_CDS <CON_LAST_MODIFIED>
J 0
(2325 375);
PAINT GREEN (2325 375);
FORCEPROP 2 LAST CUSTOM_TXT_CDS <XR_PAGE_TITLE>
J 0
(-3640 5275);
DISPLAY 0.638298 (-3640 5275);
PAINT PINK (-3640 5275);
DISPLAY INVISIBLE (-3640 5275);
FORCEPROP 1 LAST SCH_ADDRESS3 Santa Clara, CA 95052-8119
J 0
(275 50);
DISPLAY 0.617021 (275 50);
PAINT GREEN (275 50);
FORCEPROP 1 LAST SCH_ADDRESS2 P.O. BOX 58119
J 0
(275 100);
DISPLAY 0.617021 (275 100);
PAINT GREEN (275 100);
FORCEPROP 1 LAST SCH_ADDRESS1 2200 Mission College Blvd.
J 0
(275 150);
DISPLAY 0.617021 (275 150);
PAINT GREEN (275 150);
FORCEPROP 1 LAST SCH_TITLE CPU SIDE BAND: PROCHOT & MEMHOT (1/2)
J 0
(-3700 75);
DISPLAY 1.212766 (-3700 75);
PAINT ORANGE (-3700 75);
FORCEPROP 1 LAST SCH_NUMBER H4694802
J 0
(2950 175);
DISPLAY 1.212766 (2950 175);
PAINT YELLOW (2950 175);
FORCEPROP 1 LAST SCH_DEPT BESD
J 1
(-200 125);
DISPLAY 1.212766 (-200 125);
PAINT YELLOW (-200 125);
FORCEPROP 1 LAST SCH_REV 2.420
J 0
(4000 175);
DISPLAY 0.978723 (4000 175);
PAINT YELLOW (4000 175);
FORCEPROP 2 LAST CDS_LIB mstr_symbols
J 0
(4250 25);
PAINT MONO (4250 25);
DISPLAY INVISIBLE (4250 25);
FORCEPROP 2 LAST PAGE_BORDER TRUE
J 0
(-3640 5275);
DISPLAY 0.638298 (-3640 5275);
PAINT PINK (-3640 5275);
DISPLAY INVISIBLE (-3640 5275);
FORCEPROP 1 LAST COMMENT_BODY TRUE
J 0
(4262 37);
DISPLAY 0.468085 (4262 37);
PAINT GREEN (4262 37);
DISPLAY INVISIBLE (4262 37);
FORCEPROP 2 LAST CDS_XR_PAGE_TITLE CR-94 : @BASEBOARD_FAB2_LIB.BASEBOARD_FAB2(SCH_1):PAGE94
J 0
(-3640 5275);
DISPLAY 0.638298 (-3640 5275);
PAINT PINK (-3640 5275);
DISPLAY INVISIBLE (-3640 5275);
WIRE 16 -1 (175 4175)(175 4250);
WIRE 16 -1 (750 3475)(750 3275);
WIRE 16 -1 (-1425 1850)(-1425 1800);
WIRE 16 -1 (-2150 2525)(-2150 2475);
WIRE 16 -1 (-2150 1725)(-2150 1700);
WIRE 16 -1 (-1425 750)(-1425 700);
WIRE 16 -1 (-2150 1425)(-2150 1375);
WIRE 16 -1 (-2150 625)(-2150 600);
WIRE 16 -1 (1900 1900)(1900 1850);
WIRE 16 -1 (1900 800)(1900 750);
WIRE 16 -1 (1175 2575)(1175 2525);
WIRE 16 -1 (1175 1775)(1175 1750);
WIRE 16 -1 (1175 1475)(1175 1425);
WIRE 16 -1 (1175 675)(1175 650);
WIRE 16 -1 (1400 4500)(1400 4650);
WIRE 16 -1 (1400 3750)(1400 3600);
WIRE 16 -1 (175 3275)(175 3325);
WIRE 16 -1 (-300 4000)(-300 3750);
WIRE 16 -1 (-3275 1825)(-2350 1825);
FORCEPROP 0 LAST SIG_NAME IRQ_PVDDQ_ABC_VRHOT_LVT3_N
J 0
(-3285 1835);
DISPLAY 0.617021 (-3285 1835);
PAINT ORANGE (-3285 1835);
WIRE 16 -1 (-3275 725)(-2350 725);
FORCEPROP 0 LAST SIG_NAME IRQ_PVDDQ_DEF_VRHOT_LVT3_N
J 0
(-3285 735);
DISPLAY 0.617021 (-3285 735);
PAINT ORANGE (-3285 735);
WIRE 16 -1 (-1675 1050)(-1675 850);
WIRE 16 -1 (-1675 1050)(-2150 1050);
FORCEPROP 0 LAST SIG_NAME H_CPU0_MEMDEF_MEMHOT
J 0
(-2085 1060);
DISPLAY 0.617021 (-2085 1060);
PAINT ORANGE (-2085 1060);
FORCEPROP 2 LASTPROP $XRERR UNIQUE?
J 0
(-2325 1060);
DISPLAY 0.638298 (-2325 1060);
PAINT MONO (-2325 1060);
DISPLAY INVISIBLE (-2325 1060);
WIRE 16 -1 (-1675 850)(-1625 850);
WIRE 16 -1 (-2150 1050)(-2150 1175);
WIRE 16 -1 (-2150 1025)(-2150 1050);
WIRE 16 -1 (-1675 2150)(-1675 1950);
WIRE 16 -1 (-1675 2150)(-2150 2150);
FORCEPROP 0 LAST SIG_NAME H_CPU0_MEMABC_MEMHOT
J 0
(-2085 2160);
DISPLAY 0.617021 (-2085 2160);
PAINT ORANGE (-2085 2160);
FORCEPROP 2 LASTPROP $XRERR UNIQUE?
J 0
(-2325 2160);
DISPLAY 0.638298 (-2325 2160);
PAINT MONO (-2325 2160);
DISPLAY INVISIBLE (-2325 2160);
WIRE 16 -1 (-1675 1950)(-1625 1950);
WIRE 16 -1 (-2150 2150)(-2150 2275);
WIRE 16 -1 (-2150 2125)(-2150 2150);
WIRE 16 -1 (-1425 1200)(-725 1200);
FORCEPROP 2 LAST SIG_NAME H_CPU0_MEMDEF_MEMHOT_G_N
J 0
(-1402 1210);
DISPLAY 0.617021 (-1402 1210);
PAINT ORANGE (-1402 1210);
WIRE 16 -1 (-1425 1150)(-1425 1200);
WIRE 16 -1 (-1425 2300)(-725 2300);
FORCEPROP 2 LAST SIG_NAME H_CPU0_MEMABC_MEMHOT_G_N
J 0
(-1402 2310);
DISPLAY 0.617021 (-1402 2310);
PAINT ORANGE (-1402 2310);
WIRE 16 -1 (-1425 2250)(-1425 2300);
WIRE 16 -1 (-300 3550)(-300 3425);
WIRE 16 -1 (-25 3425)(-300 3425);
WIRE 16 -1 (-1600 3425)(-300 3425);
FORCEPROP 2 LAST SIG_NAME FM_DIMM_EVENT_COD_N
J 0
(-1585 3435);
DISPLAY 0.617021 (-1585 3435);
PAINT ORANGE (-1585 3435);
WIRE 16 273 (4125 2725)(-3700 2725);
WIRE 16 -1 (50 775)(975 775);
FORCEPROP 0 LAST SIG_NAME IRQ_PVDDQ_KLM_VRHOT_LVT3_N
J 0
(40 785);
DISPLAY 0.617021 (40 785);
PAINT ORANGE (40 785);
WIRE 16 -1 (50 1875)(975 1875);
FORCEPROP 0 LAST SIG_NAME IRQ_PVDDQ_GHJ_VRHOT_LVT3_N
J 0
(40 1885);
DISPLAY 0.617021 (40 1885);
PAINT ORANGE (40 1885);
WIRE 16 -1 (1650 1100)(1175 1100);
FORCEPROP 0 LAST SIG_NAME H_CPU1_MEMKLM_MEMHOT
J 0
(1240 1110);
DISPLAY 0.617021 (1240 1110);
PAINT ORANGE (1240 1110);
FORCEPROP 2 LASTPROP $XRERR UNIQUE?
J 0
(1000 1110);
DISPLAY 0.638298 (1000 1110);
PAINT MONO (1000 1110);
DISPLAY INVISIBLE (1000 1110);
WIRE 16 -1 (1650 1100)(1650 900);
WIRE 16 -1 (1175 1100)(1175 1225);
WIRE 16 -1 (1175 1075)(1175 1100);
WIRE 16 -1 (1650 900)(1700 900);
WIRE 16 -1 (1650 2200)(1175 2200);
FORCEPROP 0 LAST SIG_NAME H_CPU1_MEMGHJ_MEMHOT
J 0
(1240 2210);
DISPLAY 0.617021 (1240 2210);
PAINT ORANGE (1240 2210);
FORCEPROP 2 LASTPROP $XRERR UNIQUE?
J 0
(1000 2210);
DISPLAY 0.638298 (1000 2210);
PAINT MONO (1000 2210);
DISPLAY INVISIBLE (1000 2210);
WIRE 16 -1 (1650 2200)(1650 2000);
WIRE 16 -1 (1175 2200)(1175 2325);
WIRE 16 -1 (1175 2175)(1175 2200);
WIRE 16 -1 (1650 2000)(1700 2000);
WIRE 16 -1 (750 3675)(750 3850);
WIRE 16 -1 (750 3850)(1200 3850);
WIRE 16 -1 (175 3850)(750 3850);
FORCEPROP 2 LAST SIG_NAME FM_DIMM_EVENT_FET
J 0
(365 3860);
DISPLAY 0.617021 (365 3860);
PAINT ORANGE (365 3860);
FORCEPROP 2 LASTPROP $XRERR UNIQUE?
J 0
(125 3860);
DISPLAY 0.638298 (125 3860);
PAINT MONO (125 3860);
DISPLAY INVISIBLE (125 3860);
WIRE 16 -1 (175 3975)(175 3850);
WIRE 16 -1 (175 3725)(175 3850);
WIRE 16 -1 (1900 2350)(2600 2350);
FORCEPROP 2 LAST SIG_NAME H_CPU1_MEMGHJ_MEMHOT_G_N
J 0
(1923 2360);
DISPLAY 0.617021 (1923 2360);
PAINT ORANGE (1923 2360);
WIRE 16 -1 (1900 2300)(1900 2350);
WIRE 16 -1 (1900 1250)(2600 1250);
FORCEPROP 2 LAST SIG_NAME H_CPU1_MEMKLM_MEMHOT_G_N
J 0
(1923 1260);
DISPLAY 0.617021 (1923 1260);
PAINT ORANGE (1923 1260);
WIRE 16 -1 (1900 1200)(1900 1250);
WIRE 16 -1 (1400 4300)(1400 4250);
WIRE 16 -1 (1400 4250)(2400 4250);
FORCEPROP 2 LAST SIG_NAME FM_MEM_THERM_EVENT_LVT3_N
J 0
(1690 4260);
DISPLAY 0.617021 (1690 4260);
PAINT ORANGE (1690 4260);
WIRE 16 -1 (1400 4150)(1400 4250);
DOT 1 (750 3850);
DOT 1 (175 3850);
DOT 1 (-300 3425);
DOT 1 (-2150 2150);
DOT 1 (-2150 1050);
DOT 1 (1175 2200);
DOT 1 (1175 1100);
DOT 1 (1400 4250);
FORCENOTE
ROOM=PROC_SIDEBAND
(-3684 186) 0;
DISPLAY LEFT (-3684 186);
DISPLAY 1.276596 (-3684 186);
PAINT PURPLE (-3684 186);
QUIT
